FILE_TYPE = MACRO_DRAWING;
SET COLOR_WIRE YELLOW;
SET COLOR_PROP MONO;
SET COLOR_DOT WHITE;
SET COLOR_ARC YELLOW;
SET COLOR_BODY GREEN;
SET COLOR_NOTE MONO;
SET PROP_DISPLAY VALUE;
SET PAGE_NUMBER P54;
FORCEADD OFFPAGE..3
(1575 5200);
FORCEPROP 2 LAST $XR1 53 
J 0
(1879 5200);
DISPLAY 0.638298 (1879 5200);
PAINT MONO (1879 5200);
FORCEPROP 2 LAST $XR0 28 
J 0
(1789 5200);
DISPLAY 0.638298 (1789 5200);
PAINT MONO (1789 5200);
FORCEPROP 2 LAST PATH I1
J 0
(1775 5275);
DISPLAY 0.787234 (1775 5275);
PAINT MONO (1775 5275);
DISPLAY INVISIBLE (1775 5275);
FORCEPROP 1 LAST COMMENT_BODY TRUE
J 0
(1525 5100);
DISPLAY 0.936170 (1525 5100);
PAINT GREEN (1525 5100);
DISPLAY INVISIBLE (1525 5100);
FORCEPROP 1 LAST OFFPAGE TRUE
J 0
(1900 5075);
DISPLAY 0.936170 (1900 5075);
PAINT GREEN (1900 5075);
DISPLAY INVISIBLE (1900 5075);
FORCEPROP 2 LAST CDS_LIB mstr_standard
J 0
(1575 5200);
DISPLAY 0.787234 (1575 5200);
PAINT MONO (1575 5200);
DISPLAY INVISIBLE (1575 5200);
FORCEADD TAP..6
R 2
(700 4850);
FORCEPROP 3 LASTPIN (650 4850) SIG_NAME M_F_DQS_DP<14>
J 0
(660 4860);
DISPLAY 0.659574 (660 4860);
PAINT MONO (660 4860);
DISPLAY INVISIBLE (660 4860);
FORCEPROP 1 LASTPIN (650 4850) BN 14
J 2
(700 4860);
DISPLAY 0.617021 (700 4860);
PAINT PINK (700 4860);
FORCEPROP 1 LAST PATH I10
J 2
(700 4850);
DISPLAY 0.936170 (700 4850);
PAINT GREEN (700 4850);
DISPLAY INVISIBLE (700 4850);
FORCEPROP 1 LAST HDL_TAP TRUE
J 2
(375 4725);
DISPLAY 1.234043 (375 4725);
PAINT GREEN (375 4725);
DISPLAY INVISIBLE (375 4725);
FORCEPROP 1 LAST BODY_TYPE PLUMBING
J 2
(700 4800);
DISPLAY 1.234043 (700 4800);
PAINT GREEN (700 4800);
DISPLAY INVISIBLE (700 4800);
FORCEPROP 2 LAST CDS_LIB mstr_standard
J 0
(700 4850);
DISPLAY 0.787234 (700 4850);
PAINT MONO (700 4850);
DISPLAY INVISIBLE (700 4850);
FORCEADD TAP..6
R 2
(-1650 2050);
FORCEPROP 3 LASTPIN (-1700 2050) SIG_NAME M_F_DQ<9>
J 0
(-1690 2060);
DISPLAY 0.659574 (-1690 2060);
PAINT MONO (-1690 2060);
DISPLAY INVISIBLE (-1690 2060);
FORCEPROP 1 LASTPIN (-1700 2050) BN 9
J 2
(-1650 2060);
DISPLAY 0.617021 (-1650 2060);
PAINT PINK (-1650 2060);
FORCEPROP 1 LAST PATH I100
J 2
(-1650 2050);
DISPLAY 0.936170 (-1650 2050);
PAINT GREEN (-1650 2050);
DISPLAY INVISIBLE (-1650 2050);
FORCEPROP 1 LAST HDL_TAP TRUE
J 2
(-1975 1925);
DISPLAY 1.234043 (-1975 1925);
PAINT GREEN (-1975 1925);
DISPLAY INVISIBLE (-1975 1925);
FORCEPROP 1 LAST BODY_TYPE PLUMBING
J 2
(-1650 2000);
DISPLAY 1.234043 (-1650 2000);
PAINT GREEN (-1650 2000);
DISPLAY INVISIBLE (-1650 2000);
FORCEPROP 2 LAST CDS_LIB mstr_standard
J 2
(-1650 2050);
DISPLAY 0.787234 (-1650 2050);
PAINT MONO (-1650 2050);
DISPLAY INVISIBLE (-1650 2050);
FORCEADD TAP..6
R 2
(-1650 2100);
FORCEPROP 3 LASTPIN (-1700 2100) SIG_NAME M_F_DQ<10>
J 0
(-1690 2110);
DISPLAY 0.659574 (-1690 2110);
PAINT MONO (-1690 2110);
DISPLAY INVISIBLE (-1690 2110);
FORCEPROP 1 LASTPIN (-1700 2100) BN 10
J 2
(-1650 2110);
DISPLAY 0.617021 (-1650 2110);
PAINT PINK (-1650 2110);
FORCEPROP 1 LAST PATH I101
J 2
(-1650 2100);
DISPLAY 0.936170 (-1650 2100);
PAINT GREEN (-1650 2100);
DISPLAY INVISIBLE (-1650 2100);
FORCEPROP 1 LAST HDL_TAP TRUE
J 2
(-1975 1975);
DISPLAY 1.234043 (-1975 1975);
PAINT GREEN (-1975 1975);
DISPLAY INVISIBLE (-1975 1975);
FORCEPROP 1 LAST BODY_TYPE PLUMBING
J 2
(-1650 2050);
DISPLAY 1.234043 (-1650 2050);
PAINT GREEN (-1650 2050);
DISPLAY INVISIBLE (-1650 2050);
FORCEPROP 2 LAST CDS_LIB mstr_standard
J 2
(-1650 2100);
DISPLAY 0.787234 (-1650 2100);
PAINT MONO (-1650 2100);
DISPLAY INVISIBLE (-1650 2100);
FORCEADD TAP..6
R 2
(-1650 1800);
FORCEPROP 3 LASTPIN (-1700 1800) SIG_NAME M_F_DQ<4>
J 0
(-1690 1810);
DISPLAY 0.659574 (-1690 1810);
PAINT MONO (-1690 1810);
DISPLAY INVISIBLE (-1690 1810);
FORCEPROP 1 LASTPIN (-1700 1800) BN 4
J 2
(-1650 1810);
DISPLAY 0.617021 (-1650 1810);
PAINT PINK (-1650 1810);
FORCEPROP 1 LAST PATH I102
J 2
(-1650 1800);
DISPLAY 0.936170 (-1650 1800);
PAINT GREEN (-1650 1800);
DISPLAY INVISIBLE (-1650 1800);
FORCEPROP 1 LAST HDL_TAP TRUE
J 2
(-1975 1675);
DISPLAY 1.234043 (-1975 1675);
PAINT GREEN (-1975 1675);
DISPLAY INVISIBLE (-1975 1675);
FORCEPROP 1 LAST BODY_TYPE PLUMBING
J 2
(-1650 1750);
DISPLAY 1.234043 (-1650 1750);
PAINT GREEN (-1650 1750);
DISPLAY INVISIBLE (-1650 1750);
FORCEPROP 2 LAST CDS_LIB mstr_standard
J 2
(-1650 1800);
DISPLAY 0.787234 (-1650 1800);
PAINT MONO (-1650 1800);
DISPLAY INVISIBLE (-1650 1800);
FORCEADD TAP..6
R 2
(-1650 1750);
FORCEPROP 3 LASTPIN (-1700 1750) SIG_NAME M_F_DQ<3>
J 0
(-1690 1760);
DISPLAY 0.659574 (-1690 1760);
PAINT MONO (-1690 1760);
DISPLAY INVISIBLE (-1690 1760);
FORCEPROP 1 LASTPIN (-1700 1750) BN 3
J 2
(-1650 1760);
DISPLAY 0.617021 (-1650 1760);
PAINT PINK (-1650 1760);
FORCEPROP 1 LAST PATH I103
J 2
(-1650 1750);
DISPLAY 0.936170 (-1650 1750);
PAINT GREEN (-1650 1750);
DISPLAY INVISIBLE (-1650 1750);
FORCEPROP 1 LAST HDL_TAP TRUE
J 2
(-1975 1625);
DISPLAY 1.234043 (-1975 1625);
PAINT GREEN (-1975 1625);
DISPLAY INVISIBLE (-1975 1625);
FORCEPROP 1 LAST BODY_TYPE PLUMBING
J 2
(-1650 1700);
DISPLAY 1.234043 (-1650 1700);
PAINT GREEN (-1650 1700);
DISPLAY INVISIBLE (-1650 1700);
FORCEPROP 2 LAST CDS_LIB mstr_standard
J 2
(-1650 1750);
DISPLAY 0.787234 (-1650 1750);
PAINT MONO (-1650 1750);
DISPLAY INVISIBLE (-1650 1750);
FORCEADD TAP..6
R 2
(-1650 1850);
FORCEPROP 3 LASTPIN (-1700 1850) SIG_NAME M_F_DQ<5>
J 0
(-1690 1860);
DISPLAY 0.659574 (-1690 1860);
PAINT MONO (-1690 1860);
DISPLAY INVISIBLE (-1690 1860);
FORCEPROP 1 LASTPIN (-1700 1850) BN 5
J 2
(-1650 1860);
DISPLAY 0.617021 (-1650 1860);
PAINT PINK (-1650 1860);
FORCEPROP 1 LAST PATH I104
J 2
(-1650 1850);
DISPLAY 0.936170 (-1650 1850);
PAINT GREEN (-1650 1850);
DISPLAY INVISIBLE (-1650 1850);
FORCEPROP 1 LAST HDL_TAP TRUE
J 2
(-1975 1725);
DISPLAY 1.234043 (-1975 1725);
PAINT GREEN (-1975 1725);
DISPLAY INVISIBLE (-1975 1725);
FORCEPROP 1 LAST BODY_TYPE PLUMBING
J 2
(-1650 1800);
DISPLAY 1.234043 (-1650 1800);
PAINT GREEN (-1650 1800);
DISPLAY INVISIBLE (-1650 1800);
FORCEPROP 2 LAST CDS_LIB mstr_standard
J 2
(-1650 1850);
DISPLAY 0.787234 (-1650 1850);
PAINT MONO (-1650 1850);
DISPLAY INVISIBLE (-1650 1850);
FORCEADD TAP..6
R 2
(-1650 1900);
FORCEPROP 3 LASTPIN (-1700 1900) SIG_NAME M_F_DQ<6>
J 0
(-1690 1910);
DISPLAY 0.659574 (-1690 1910);
PAINT MONO (-1690 1910);
DISPLAY INVISIBLE (-1690 1910);
FORCEPROP 1 LASTPIN (-1700 1900) BN 6
J 2
(-1650 1910);
DISPLAY 0.617021 (-1650 1910);
PAINT PINK (-1650 1910);
FORCEPROP 1 LAST PATH I105
J 2
(-1650 1900);
DISPLAY 0.936170 (-1650 1900);
PAINT GREEN (-1650 1900);
DISPLAY INVISIBLE (-1650 1900);
FORCEPROP 1 LAST HDL_TAP TRUE
J 2
(-1975 1775);
DISPLAY 1.234043 (-1975 1775);
PAINT GREEN (-1975 1775);
DISPLAY INVISIBLE (-1975 1775);
FORCEPROP 1 LAST BODY_TYPE PLUMBING
J 2
(-1650 1850);
DISPLAY 1.234043 (-1650 1850);
PAINT GREEN (-1650 1850);
DISPLAY INVISIBLE (-1650 1850);
FORCEPROP 2 LAST CDS_LIB mstr_standard
J 2
(-1650 1900);
DISPLAY 0.787234 (-1650 1900);
PAINT MONO (-1650 1900);
DISPLAY INVISIBLE (-1650 1900);
FORCEADD TAP..6
R 2
(-1650 2000);
FORCEPROP 3 LASTPIN (-1700 2000) SIG_NAME M_F_DQ<8>
J 0
(-1690 2010);
DISPLAY 0.659574 (-1690 2010);
PAINT MONO (-1690 2010);
DISPLAY INVISIBLE (-1690 2010);
FORCEPROP 1 LASTPIN (-1700 2000) BN 8
J 2
(-1650 2010);
DISPLAY 0.617021 (-1650 2010);
PAINT PINK (-1650 2010);
FORCEPROP 1 LAST PATH I106
J 2
(-1650 2000);
DISPLAY 0.936170 (-1650 2000);
PAINT GREEN (-1650 2000);
DISPLAY INVISIBLE (-1650 2000);
FORCEPROP 1 LAST HDL_TAP TRUE
J 2
(-1975 1875);
DISPLAY 1.234043 (-1975 1875);
PAINT GREEN (-1975 1875);
DISPLAY INVISIBLE (-1975 1875);
FORCEPROP 1 LAST BODY_TYPE PLUMBING
J 2
(-1650 1950);
DISPLAY 1.234043 (-1650 1950);
PAINT GREEN (-1650 1950);
DISPLAY INVISIBLE (-1650 1950);
FORCEPROP 2 LAST CDS_LIB mstr_standard
J 2
(-1650 2000);
DISPLAY 0.787234 (-1650 2000);
PAINT MONO (-1650 2000);
DISPLAY INVISIBLE (-1650 2000);
FORCEADD TAP..6
R 2
(-1650 1950);
FORCEPROP 3 LASTPIN (-1700 1950) SIG_NAME M_F_DQ<7>
J 0
(-1690 1960);
DISPLAY 0.659574 (-1690 1960);
PAINT MONO (-1690 1960);
DISPLAY INVISIBLE (-1690 1960);
FORCEPROP 1 LASTPIN (-1700 1950) BN 7
J 2
(-1650 1960);
DISPLAY 0.617021 (-1650 1960);
PAINT PINK (-1650 1960);
FORCEPROP 1 LAST PATH I107
J 2
(-1650 1950);
DISPLAY 0.936170 (-1650 1950);
PAINT GREEN (-1650 1950);
DISPLAY INVISIBLE (-1650 1950);
FORCEPROP 1 LAST HDL_TAP TRUE
J 2
(-1975 1825);
DISPLAY 1.234043 (-1975 1825);
PAINT GREEN (-1975 1825);
DISPLAY INVISIBLE (-1975 1825);
FORCEPROP 1 LAST BODY_TYPE PLUMBING
J 2
(-1650 1900);
DISPLAY 1.234043 (-1650 1900);
PAINT GREEN (-1650 1900);
DISPLAY INVISIBLE (-1650 1900);
FORCEPROP 2 LAST CDS_LIB mstr_standard
J 2
(-1650 1950);
DISPLAY 0.787234 (-1650 1950);
PAINT MONO (-1650 1950);
DISPLAY INVISIBLE (-1650 1950);
FORCEADD TAP..6
R 2
(-1650 1600);
FORCEPROP 3 LASTPIN (-1700 1600) SIG_NAME M_F_DQ<0>
J 0
(-1690 1610);
DISPLAY 0.659574 (-1690 1610);
PAINT MONO (-1690 1610);
DISPLAY INVISIBLE (-1690 1610);
FORCEPROP 1 LASTPIN (-1700 1600) BN 0
J 2
(-1650 1610);
DISPLAY 0.617021 (-1650 1610);
PAINT PINK (-1650 1610);
FORCEPROP 1 LAST PATH I108
J 2
(-1650 1600);
DISPLAY 0.936170 (-1650 1600);
PAINT GREEN (-1650 1600);
DISPLAY INVISIBLE (-1650 1600);
FORCEPROP 1 LAST HDL_TAP TRUE
J 2
(-1975 1475);
DISPLAY 1.234043 (-1975 1475);
PAINT GREEN (-1975 1475);
DISPLAY INVISIBLE (-1975 1475);
FORCEPROP 1 LAST BODY_TYPE PLUMBING
J 2
(-1650 1550);
DISPLAY 1.234043 (-1650 1550);
PAINT GREEN (-1650 1550);
DISPLAY INVISIBLE (-1650 1550);
FORCEPROP 2 LAST CDS_LIB mstr_standard
J 2
(-1650 1600);
DISPLAY 0.787234 (-1650 1600);
PAINT MONO (-1650 1600);
DISPLAY INVISIBLE (-1650 1600);
FORCEADD TAP..6
R 2
(-1650 1700);
FORCEPROP 3 LASTPIN (-1700 1700) SIG_NAME M_F_DQ<2>
J 0
(-1690 1710);
DISPLAY 0.659574 (-1690 1710);
PAINT MONO (-1690 1710);
DISPLAY INVISIBLE (-1690 1710);
FORCEPROP 1 LASTPIN (-1700 1700) BN 2
J 2
(-1650 1710);
DISPLAY 0.617021 (-1650 1710);
PAINT PINK (-1650 1710);
FORCEPROP 1 LAST PATH I109
J 2
(-1650 1700);
DISPLAY 0.936170 (-1650 1700);
PAINT GREEN (-1650 1700);
DISPLAY INVISIBLE (-1650 1700);
FORCEPROP 1 LAST HDL_TAP TRUE
J 2
(-1975 1575);
DISPLAY 1.234043 (-1975 1575);
PAINT GREEN (-1975 1575);
DISPLAY INVISIBLE (-1975 1575);
FORCEPROP 1 LAST BODY_TYPE PLUMBING
J 2
(-1650 1650);
DISPLAY 1.234043 (-1650 1650);
PAINT GREEN (-1650 1650);
DISPLAY INVISIBLE (-1650 1650);
FORCEPROP 2 LAST CDS_LIB mstr_standard
J 2
(-1650 1700);
DISPLAY 0.787234 (-1650 1700);
PAINT MONO (-1650 1700);
DISPLAY INVISIBLE (-1650 1700);
FORCEADD TAP..6
R 2
(700 4950);
FORCEPROP 3 LASTPIN (650 4950) SIG_NAME M_F_DQS_DP<15>
J 0
(660 4960);
DISPLAY 0.659574 (660 4960);
PAINT MONO (660 4960);
DISPLAY INVISIBLE (660 4960);
FORCEPROP 1 LASTPIN (650 4950) BN 15
J 2
(700 4960);
DISPLAY 0.617021 (700 4960);
PAINT PINK (700 4960);
FORCEPROP 1 LAST PATH I11
J 2
(700 4950);
DISPLAY 0.936170 (700 4950);
PAINT GREEN (700 4950);
DISPLAY INVISIBLE (700 4950);
FORCEPROP 1 LAST HDL_TAP TRUE
J 2
(375 4825);
DISPLAY 1.234043 (375 4825);
PAINT GREEN (375 4825);
DISPLAY INVISIBLE (375 4825);
FORCEPROP 1 LAST BODY_TYPE PLUMBING
J 2
(700 4900);
DISPLAY 1.234043 (700 4900);
PAINT GREEN (700 4900);
DISPLAY INVISIBLE (700 4900);
FORCEPROP 2 LAST CDS_LIB mstr_standard
J 0
(700 4950);
DISPLAY 0.787234 (700 4950);
PAINT MONO (700 4950);
DISPLAY INVISIBLE (700 4950);
FORCEADD TAP..6
R 2
(-1650 1650);
FORCEPROP 3 LASTPIN (-1700 1650) SIG_NAME M_F_DQ<1>
J 0
(-1690 1660);
DISPLAY 0.659574 (-1690 1660);
PAINT MONO (-1690 1660);
DISPLAY INVISIBLE (-1690 1660);
FORCEPROP 1 LASTPIN (-1700 1650) BN 1
J 2
(-1650 1660);
DISPLAY 0.617021 (-1650 1660);
PAINT PINK (-1650 1660);
FORCEPROP 1 LAST PATH I110
J 2
(-1650 1650);
DISPLAY 0.936170 (-1650 1650);
PAINT GREEN (-1650 1650);
DISPLAY INVISIBLE (-1650 1650);
FORCEPROP 1 LAST HDL_TAP TRUE
J 2
(-1975 1525);
DISPLAY 1.234043 (-1975 1525);
PAINT GREEN (-1975 1525);
DISPLAY INVISIBLE (-1975 1525);
FORCEPROP 1 LAST BODY_TYPE PLUMBING
J 2
(-1650 1600);
DISPLAY 1.234043 (-1650 1600);
PAINT GREEN (-1650 1600);
DISPLAY INVISIBLE (-1650 1600);
FORCEPROP 2 LAST CDS_LIB mstr_standard
J 2
(-1650 1650);
DISPLAY 0.787234 (-1650 1650);
PAINT MONO (-1650 1650);
DISPLAY INVISIBLE (-1650 1650);
FORCEADD SCONN288_H44441003..1
(-2400 3100);
FORCEPROP 2 LASTPIN (-1900 3250) $PN 242
J 0
(-1890 3260);
DISPLAY 0.617021 (-1890 3260);
PAINT ORANGE (-1890 3260);
FORCEPROP 2 LASTPIN (-1900 3100) $PN 43
J 0
(-1890 3110);
DISPLAY 0.617021 (-1890 3110);
PAINT ORANGE (-1890 3110);
FORCEPROP 2 LASTPIN (-1900 3050) $PN 181
J 0
(-1890 3060);
DISPLAY 0.617021 (-1890 3060);
PAINT ORANGE (-1890 3060);
FORCEPROP 2 LASTPIN (-1900 3000) $PN 36
J 0
(-1890 3010);
DISPLAY 0.617021 (-1890 3010);
PAINT ORANGE (-1890 3010);
FORCEPROP 2 LASTPIN (-1900 2950) $PN 190
J 0
(-1890 2960);
DISPLAY 0.617021 (-1890 2960);
PAINT ORANGE (-1890 2960);
FORCEPROP 2 LASTPIN (-1900 3900) $PN 113
J 0
(-1890 3910);
DISPLAY 0.617021 (-1890 3910);
PAINT ORANGE (-1890 3910);
FORCEPROP 2 LASTPIN (-2900 4400) $PN 225
J 2
(-2910 4410);
DISPLAY 0.617021 (-2910 4410);
PAINT ORANGE (-2910 4410);
FORCEPROP 1 LAST MATERIAL SCONN
J 0
(-2850 4950);
DISPLAY 0.617021 (-2850 4950);
PAINT SKYBLUE (-2850 4950);
FORCEPROP 1 LAST LOCATION J6L1
J 0
(-2850 5000);
DISPLAY 0.617021 (-2850 5000);
PAINT AQUA (-2850 5000);
FORCEPROP 2 LASTPIN (-1900 4600) $PN 128
J 0
(-1890 4610);
DISPLAY 0.617021 (-1890 4610);
PAINT ORANGE (-1890 4610);
FORCEPROP 2 LASTPIN (-2900 4750) $PN 234
J 2
(-2910 4760);
DISPLAY 0.617021 (-2910 4760);
PAINT ORANGE (-2910 4760);
FORCEPROP 2 LASTPIN (-1900 3600) $PN 108
J 0
(-1890 3610);
DISPLAY 0.617021 (-1890 3610);
PAINT ORANGE (-1890 3610);
FORCEPROP 2 LASTPIN (-1900 3650) $PN 253
J 0
(-1890 3660);
DISPLAY 0.617021 (-1890 3660);
PAINT ORANGE (-1890 3660);
FORCEPROP 2 LASTPIN (-1900 3700) $PN 115
J 0
(-1890 3710);
DISPLAY 0.617021 (-1890 3710);
PAINT ORANGE (-1890 3710);
FORCEPROP 2 LASTPIN (-1900 3800) $PN 106
J 0
(-1890 3810);
DISPLAY 0.617021 (-1890 3810);
PAINT ORANGE (-1890 3810);
FORCEPROP 2 LASTPIN (-1900 3850) $PN 251
J 0
(-1890 3860);
DISPLAY 0.617021 (-1890 3860);
PAINT ORANGE (-1890 3860);
FORCEPROP 2 LASTPIN (-1900 1650) $PN 150
J 0
(-1890 1660);
DISPLAY 0.617021 (-1890 1660);
PAINT ORANGE (-1890 1660);
FORCEPROP 2 LASTPIN (-2900 3900) $PN 79
J 2
(-2910 3910);
DISPLAY 0.617021 (-2910 3910);
PAINT ORANGE (-2910 3910);
FORCEPROP 2 LASTPIN (-2900 3950) $PN 72
J 2
(-2910 3960);
DISPLAY 0.617021 (-2910 3960);
PAINT ORANGE (-2910 3960);
FORCEPROP 2 LASTPIN (-2900 4050) $PN 71
J 2
(-2910 4060);
DISPLAY 0.617021 (-2910 4060);
PAINT ORANGE (-2910 4060);
FORCEPROP 2 LASTPIN (-2900 4100) $PN 214
J 2
(-2910 4110);
DISPLAY 0.617021 (-2910 4110);
PAINT ORANGE (-2910 4110);
FORCEPROP 2 LASTPIN (-2900 4150) $PN 213
J 2
(-2910 4160);
DISPLAY 0.617021 (-2910 4160);
PAINT ORANGE (-2910 4160);
FORCEPROP 2 LASTPIN (-2900 4200) $PN 69
J 2
(-2910 4210);
DISPLAY 0.617021 (-2910 4210);
PAINT ORANGE (-2910 4210);
FORCEPROP 2 LASTPIN (-2900 4250) $PN 211
J 2
(-2910 4260);
DISPLAY 0.617021 (-2910 4260);
PAINT ORANGE (-2910 4260);
FORCEPROP 2 LASTPIN (-2900 4300) $PN 68
J 2
(-2910 4310);
DISPLAY 0.617021 (-2910 4310);
PAINT ORANGE (-2910 4310);
FORCEPROP 2 LASTPIN (-2900 4350) $PN 66
J 2
(-2910 4360);
DISPLAY 0.617021 (-2910 4360);
PAINT ORANGE (-2910 4360);
FORCEPROP 2 LASTPIN (-2900 4450) $PN 210
J 2
(-2910 4460);
DISPLAY 0.617021 (-2910 4460);
PAINT ORANGE (-2910 4460);
FORCEPROP 2 LASTPIN (-2900 4500) $PN 65
J 2
(-2910 4510);
DISPLAY 0.617021 (-2910 4510);
PAINT ORANGE (-2910 4510);
FORCEPROP 2 LASTPIN (-2900 4550) $PN 232
J 2
(-2910 4560);
DISPLAY 0.617021 (-2910 4560);
PAINT ORANGE (-2910 4560);
FORCEPROP 2 LASTPIN (-2900 4600) $PN 228
J 2
(-2910 4610);
DISPLAY 0.617021 (-2910 4610);
PAINT ORANGE (-2910 4610);
FORCEPROP 2 LASTPIN (-2900 4650) $PN 86
J 2
(-2910 4660);
DISPLAY 0.617021 (-2910 4660);
PAINT ORANGE (-2910 4660);
FORCEPROP 2 LASTPIN (-2900 4700) $PN 82
J 2
(-2910 4710);
DISPLAY 0.617021 (-2910 4710);
PAINT ORANGE (-2910 4710);
FORCEPROP 2 LASTPIN (-2900 2050) $PN 62
J 2
(-2910 2060);
DISPLAY 0.617021 (-2910 2060);
PAINT ORANGE (-2910 2060);
FORCEPROP 2 LASTPIN (-2900 2100) $PN 208
J 2
(-2910 2110);
DISPLAY 0.617021 (-2910 2110);
PAINT ORANGE (-2910 2110);
FORCEPROP 2 LASTPIN (-2900 3750) $PN 81
J 2
(-2910 3760);
DISPLAY 0.617021 (-2910 3760);
PAINT ORANGE (-2910 3760);
FORCEPROP 2 LASTPIN (-2900 3800) $PN 224
J 2
(-2910 3810);
DISPLAY 0.617021 (-2910 3810);
PAINT ORANGE (-2910 3810);
FORCEPROP 2 LASTPIN (-2900 3650) $PN 63
J 2
(-2910 3660);
DISPLAY 0.617021 (-2910 3660);
PAINT ORANGE (-2910 3660);
FORCEPROP 2 LASTPIN (-2900 3700) $PN 207
J 2
(-2910 3710);
DISPLAY 0.617021 (-2910 3710);
PAINT ORANGE (-2910 3710);
FORCEPROP 2 LASTPIN (-2900 3300) $PN 235
J 2
(-2910 3310);
DISPLAY 0.617021 (-2910 3310);
PAINT ORANGE (-2910 3310);
FORCEPROP 2 LASTPIN (-2900 2350) $PN 49
J 2
(-2910 2360);
DISPLAY 0.617021 (-2910 2360);
PAINT ORANGE (-2910 2360);
FORCEPROP 2 LASTPIN (-2900 2400) $PN 194
J 2
(-2910 2410);
DISPLAY 0.617021 (-2910 2410);
PAINT ORANGE (-2910 2410);
FORCEPROP 2 LASTPIN (-2900 2450) $PN 56
J 2
(-2910 2460);
DISPLAY 0.617021 (-2910 2460);
PAINT ORANGE (-2910 2460);
FORCEPROP 2 LASTPIN (-2900 2500) $PN 201
J 2
(-2910 2510);
DISPLAY 0.617021 (-2910 2510);
PAINT ORANGE (-2910 2510);
FORCEPROP 2 LASTPIN (-2900 2550) $PN 47
J 2
(-2910 2560);
DISPLAY 0.617021 (-2910 2560);
PAINT ORANGE (-2910 2560);
FORCEPROP 2 LASTPIN (-2900 2600) $PN 192
J 2
(-2910 2610);
DISPLAY 0.617021 (-2910 2610);
PAINT ORANGE (-2910 2610);
FORCEPROP 2 LASTPIN (-2900 2650) $PN 54
J 2
(-2910 2660);
DISPLAY 0.617021 (-2910 2660);
PAINT ORANGE (-2910 2660);
FORCEPROP 2 LASTPIN (-2900 2700) $PN 199
J 2
(-2910 2710);
DISPLAY 0.617021 (-2910 2710);
PAINT ORANGE (-2910 2710);
FORCEPROP 2 LASTPIN (-2900 3400) $PN 75
J 2
(-2910 3410);
DISPLAY 0.617021 (-2910 3410);
PAINT ORANGE (-2910 3410);
FORCEPROP 2 LASTPIN (-2900 3450) $PN 74
J 2
(-2910 3460);
DISPLAY 0.617021 (-2910 3460);
PAINT ORANGE (-2910 3460);
FORCEPROP 2 LASTPIN (-2900 3500) $PN 219
J 2
(-2910 3510);
DISPLAY 0.617021 (-2910 3510);
PAINT ORANGE (-2910 3510);
FORCEPROP 2 LASTPIN (-2900 3550) $PN 218
J 2
(-2910 3560);
DISPLAY 0.617021 (-2910 3560);
PAINT ORANGE (-2910 3560);
FORCEPROP 2 LASTPIN (-2900 2950) $PN 60
J 2
(-2910 2960);
DISPLAY 0.617021 (-2910 2960);
PAINT ORANGE (-2910 2960);
FORCEPROP 2 LASTPIN (-2900 3000) $PN 203
J 2
(-2910 3010);
DISPLAY 0.617021 (-2910 3010);
PAINT ORANGE (-2910 3010);
FORCEPROP 2 LASTPIN (-1900 1600) $PN 5
J 0
(-1890 1610);
DISPLAY 0.617021 (-1890 1610);
PAINT ORANGE (-1890 1610);
FORCEPROP 2 LASTPIN (-1900 1700) $PN 12
J 0
(-1890 1710);
DISPLAY 0.617021 (-1890 1710);
PAINT ORANGE (-1890 1710);
FORCEPROP 2 LASTPIN (-1900 1750) $PN 157
J 0
(-1890 1760);
DISPLAY 0.617021 (-1890 1760);
PAINT ORANGE (-1890 1760);
FORCEPROP 2 LASTPIN (-1900 1800) $PN 3
J 0
(-1890 1810);
DISPLAY 0.617021 (-1890 1810);
PAINT ORANGE (-1890 1810);
FORCEPROP 2 LASTPIN (-1900 1850) $PN 148
J 0
(-1890 1860);
DISPLAY 0.617021 (-1890 1860);
PAINT ORANGE (-1890 1860);
FORCEPROP 2 LASTPIN (-1900 1900) $PN 10
J 0
(-1890 1910);
DISPLAY 0.617021 (-1890 1910);
PAINT ORANGE (-1890 1910);
FORCEPROP 2 LASTPIN (-1900 1950) $PN 155
J 0
(-1890 1960);
DISPLAY 0.617021 (-1890 1960);
PAINT ORANGE (-1890 1960);
FORCEPROP 2 LASTPIN (-1900 2000) $PN 16
J 0
(-1890 2010);
DISPLAY 0.617021 (-1890 2010);
PAINT ORANGE (-1890 2010);
FORCEPROP 2 LASTPIN (-1900 2050) $PN 161
J 0
(-1890 2060);
DISPLAY 0.617021 (-1890 2060);
PAINT ORANGE (-1890 2060);
FORCEPROP 2 LASTPIN (-1900 2100) $PN 23
J 0
(-1890 2110);
DISPLAY 0.617021 (-1890 2110);
PAINT ORANGE (-1890 2110);
FORCEPROP 2 LASTPIN (-1900 2150) $PN 168
J 0
(-1890 2160);
DISPLAY 0.617021 (-1890 2160);
PAINT ORANGE (-1890 2160);
FORCEPROP 2 LASTPIN (-1900 2200) $PN 14
J 0
(-1890 2210);
DISPLAY 0.617021 (-1890 2210);
PAINT ORANGE (-1890 2210);
FORCEPROP 2 LASTPIN (-1900 2250) $PN 159
J 0
(-1890 2260);
DISPLAY 0.617021 (-1890 2260);
PAINT ORANGE (-1890 2260);
FORCEPROP 2 LASTPIN (-1900 2300) $PN 21
J 0
(-1890 2310);
DISPLAY 0.617021 (-1890 2310);
PAINT ORANGE (-1890 2310);
FORCEPROP 2 LASTPIN (-1900 2350) $PN 166
J 0
(-1890 2360);
DISPLAY 0.617021 (-1890 2360);
PAINT ORANGE (-1890 2360);
FORCEPROP 2 LASTPIN (-1900 2400) $PN 27
J 0
(-1890 2410);
DISPLAY 0.617021 (-1890 2410);
PAINT ORANGE (-1890 2410);
FORCEPROP 2 LASTPIN (-1900 2450) $PN 172
J 0
(-1890 2460);
DISPLAY 0.617021 (-1890 2460);
PAINT ORANGE (-1890 2460);
FORCEPROP 2 LASTPIN (-1900 2500) $PN 34
J 0
(-1890 2510);
DISPLAY 0.617021 (-1890 2510);
PAINT ORANGE (-1890 2510);
FORCEPROP 2 LASTPIN (-1900 2550) $PN 179
J 0
(-1890 2560);
DISPLAY 0.617021 (-1890 2560);
PAINT ORANGE (-1890 2560);
FORCEPROP 2 LASTPIN (-1900 2600) $PN 25
J 0
(-1890 2610);
DISPLAY 0.617021 (-1890 2610);
PAINT ORANGE (-1890 2610);
FORCEPROP 2 LASTPIN (-1900 2650) $PN 170
J 0
(-1890 2660);
DISPLAY 0.617021 (-1890 2660);
PAINT ORANGE (-1890 2660);
FORCEPROP 2 LASTPIN (-1900 2700) $PN 32
J 0
(-1890 2710);
DISPLAY 0.617021 (-1890 2710);
PAINT ORANGE (-1890 2710);
FORCEPROP 2 LASTPIN (-1900 2750) $PN 177
J 0
(-1890 2760);
DISPLAY 0.617021 (-1890 2760);
PAINT ORANGE (-1890 2760);
FORCEPROP 2 LASTPIN (-1900 2800) $PN 38
J 0
(-1890 2810);
DISPLAY 0.617021 (-1890 2810);
PAINT ORANGE (-1890 2810);
FORCEPROP 2 LASTPIN (-1900 2850) $PN 183
J 0
(-1890 2860);
DISPLAY 0.617021 (-1890 2860);
PAINT ORANGE (-1890 2860);
FORCEPROP 2 LASTPIN (-1900 2900) $PN 45
J 0
(-1890 2910);
DISPLAY 0.617021 (-1890 2910);
PAINT ORANGE (-1890 2910);
FORCEPROP 2 LASTPIN (-1900 3150) $PN 188
J 0
(-1890 3160);
DISPLAY 0.617021 (-1890 3160);
PAINT ORANGE (-1890 3160);
FORCEPROP 2 LASTPIN (-1900 3200) $PN 97
J 0
(-1890 3210);
DISPLAY 0.617021 (-1890 3210);
PAINT ORANGE (-1890 3210);
FORCEPROP 2 LASTPIN (-1900 3300) $PN 104
J 0
(-1890 3310);
DISPLAY 0.617021 (-1890 3310);
PAINT ORANGE (-1890 3310);
FORCEPROP 2 LASTPIN (-1900 3350) $PN 249
J 0
(-1890 3360);
DISPLAY 0.617021 (-1890 3360);
PAINT ORANGE (-1890 3360);
FORCEPROP 2 LASTPIN (-1900 3400) $PN 95
J 0
(-1890 3410);
DISPLAY 0.617021 (-1890 3410);
PAINT ORANGE (-1890 3410);
FORCEPROP 2 LASTPIN (-1900 3450) $PN 240
J 0
(-1890 3460);
DISPLAY 0.617021 (-1890 3460);
PAINT ORANGE (-1890 3460);
FORCEPROP 2 LASTPIN (-1900 3500) $PN 102
J 0
(-1890 3510);
DISPLAY 0.617021 (-1890 3510);
PAINT ORANGE (-1890 3510);
FORCEPROP 2 LASTPIN (-1900 3550) $PN 247
J 0
(-1890 3560);
DISPLAY 0.617021 (-1890 3560);
PAINT ORANGE (-1890 3560);
FORCEPROP 2 LASTPIN (-1900 3750) $PN 260
J 0
(-1890 3760);
DISPLAY 0.617021 (-1890 3760);
PAINT ORANGE (-1890 3760);
FORCEPROP 2 LASTPIN (-1900 3950) $PN 258
J 0
(-1890 3960);
DISPLAY 0.617021 (-1890 3960);
PAINT ORANGE (-1890 3960);
FORCEPROP 2 LASTPIN (-1900 4000) $PN 119
J 0
(-1890 4010);
DISPLAY 0.617021 (-1890 4010);
PAINT ORANGE (-1890 4010);
FORCEPROP 2 LASTPIN (-1900 4050) $PN 264
J 0
(-1890 4060);
DISPLAY 0.617021 (-1890 4060);
PAINT ORANGE (-1890 4060);
FORCEPROP 2 LASTPIN (-1900 4100) $PN 126
J 0
(-1890 4110);
DISPLAY 0.617021 (-1890 4110);
PAINT ORANGE (-1890 4110);
FORCEPROP 2 LASTPIN (-1900 4150) $PN 271
J 0
(-1890 4160);
DISPLAY 0.617021 (-1890 4160);
PAINT ORANGE (-1890 4160);
FORCEPROP 2 LASTPIN (-1900 4200) $PN 117
J 0
(-1890 4210);
DISPLAY 0.617021 (-1890 4210);
PAINT ORANGE (-1890 4210);
FORCEPROP 2 LASTPIN (-1900 4250) $PN 262
J 0
(-1890 4260);
DISPLAY 0.617021 (-1890 4260);
PAINT ORANGE (-1890 4260);
FORCEPROP 2 LASTPIN (-1900 4300) $PN 124
J 0
(-1890 4310);
DISPLAY 0.617021 (-1890 4310);
PAINT ORANGE (-1890 4310);
FORCEPROP 2 LASTPIN (-1900 4350) $PN 269
J 0
(-1890 4360);
DISPLAY 0.617021 (-1890 4360);
PAINT ORANGE (-1890 4360);
FORCEPROP 2 LASTPIN (-1900 4400) $PN 130
J 0
(-1890 4410);
DISPLAY 0.617021 (-1890 4410);
PAINT ORANGE (-1890 4410);
FORCEPROP 2 LASTPIN (-1900 4450) $PN 275
J 0
(-1890 4460);
DISPLAY 0.617021 (-1890 4460);
PAINT ORANGE (-1890 4460);
FORCEPROP 2 LASTPIN (-1900 4500) $PN 137
J 0
(-1890 4510);
DISPLAY 0.617021 (-1890 4510);
PAINT ORANGE (-1890 4510);
FORCEPROP 2 LASTPIN (-1900 4550) $PN 282
J 0
(-1890 4560);
DISPLAY 0.617021 (-1890 4560);
PAINT ORANGE (-1890 4560);
FORCEPROP 2 LASTPIN (-1900 4650) $PN 273
J 0
(-1890 4660);
DISPLAY 0.617021 (-1890 4660);
PAINT ORANGE (-1890 4660);
FORCEPROP 2 LASTPIN (-1900 4700) $PN 135
J 0
(-1890 4710);
DISPLAY 0.617021 (-1890 4710);
PAINT ORANGE (-1890 4710);
FORCEPROP 2 LASTPIN (-1900 4750) $PN 280
J 0
(-1890 4760);
DISPLAY 0.617021 (-1890 4760);
PAINT ORANGE (-1890 4760);
FORCEPROP 2 LASTPIN (-2900 2150) $PN 78
J 2
(-2910 2160);
DISPLAY 0.617021 (-2910 2160);
PAINT ORANGE (-2910 2160);
FORCEPROP 2 LASTPIN (-2900 2800) $PN 87
J 2
(-2910 2810);
DISPLAY 0.617021 (-2910 2810);
PAINT ORANGE (-2910 2810);
FORCEPROP 2 LASTPIN (-2900 2850) $PN 91
J 2
(-2910 2860);
DISPLAY 0.617021 (-2910 2860);
PAINT ORANGE (-2910 2860);
FORCEPROP 2 LASTPIN (-2900 2250) $PN 222
J 2
(-2910 2260);
DISPLAY 0.617021 (-2910 2260);
PAINT ORANGE (-2910 2260);
FORCEPROP 2 LASTPIN (-2900 2200) $PN 58
J 2
(-2910 2210);
DISPLAY 0.617021 (-2910 2210);
PAINT ORANGE (-2910 2210);
FORCEPROP 2 LASTPIN (-2900 1400) $PN 205
J 2
(-2910 1410);
DISPLAY 0.617021 (-2910 1410);
PAINT ORANGE (-2910 1410);
FORCEPROP 2 LASTPIN (-2900 1450) $PN 227
J 2
(-2910 1460);
DISPLAY 0.617021 (-2910 1460);
PAINT ORANGE (-2910 1460);
FORCEPROP 2 LASTPIN (-2900 1500) $PN 144
J 2
(-2910 1510);
DISPLAY 0.617021 (-2910 1510);
PAINT ORANGE (-2910 1510);
FORCEPROP 2 LASTPIN (-2900 3100) $PN 84
J 2
(-2910 3110);
DISPLAY 0.617021 (-2910 3110);
PAINT ORANGE (-2910 3110);
FORCEPROP 2 LASTPIN (-2900 3150) $PN 89
J 2
(-2910 3160);
DISPLAY 0.617021 (-2910 3160);
PAINT ORANGE (-2910 3160);
FORCEPROP 2 LASTPIN (-2900 3200) $PN 93
J 2
(-2910 3210);
DISPLAY 0.617021 (-2910 3210);
PAINT ORANGE (-2910 3210);
FORCEPROP 2 LASTPIN (-2900 3250) $PN 237
J 2
(-2910 3260);
DISPLAY 0.617021 (-2910 3260);
PAINT ORANGE (-2910 3260);
FORCEPROP 2 LASTPIN (-2900 1800) $PN 139
J 2
(-2910 1810);
DISPLAY 0.617021 (-2910 1810);
PAINT ORANGE (-2910 1810);
FORCEPROP 2 LASTPIN (-2900 1850) $PN 140
J 2
(-2910 1860);
DISPLAY 0.617021 (-2910 1860);
PAINT ORANGE (-2910 1860);
FORCEPROP 2 LASTPIN (-2900 1900) $PN 238
J 2
(-2910 1910);
DISPLAY 0.617021 (-2910 1910);
PAINT ORANGE (-2910 1910);
FORCEPROP 2 LASTPIN (-2900 1300) $PN 230
J 2
(-2910 1310);
DISPLAY 0.617021 (-2910 1310);
PAINT ORANGE (-2910 1310);
FORCEPROP 2 LASTPIN (-2900 1700) $PN 141
J 2
(-2910 1710);
DISPLAY 0.617021 (-2910 1710);
PAINT ORANGE (-2910 1710);
FORCEPROP 2 LASTPIN (-2900 1750) $PN 285
J 2
(-2910 1760);
DISPLAY 0.617021 (-2910 1760);
PAINT ORANGE (-2910 1760);
FORCEPROP 2 LASTPIN (-2900 1950) $PN 284
J 2
(-2910 1960);
DISPLAY 0.617021 (-2910 1960);
PAINT ORANGE (-2910 1960);
FORCEPROP 2 LASTPIN (-2900 1600) $PN 146
J 2
(-2910 1610);
DISPLAY 0.617021 (-2910 1610);
PAINT ORANGE (-2910 1610);
FORCEPROP 1 LAST PART_NUMBER H44441-003
J 0
(-2850 1100);
DISPLAY 0.617021 (-2850 1100);
PAINT BLUE (-2850 1100);
FORCEPROP 0 LAST BOM_SS NOPOP
J 0
(-2850 5100);
DISPLAY 1.021277 (-2850 5100);
PAINT BROWN (-2850 5100);
DISPLAY BOTH (-2850 5100);
FORCEPROP 2 LASTPIN (-2900 4000) $PN 216
J 2
(-2910 4010);
DISPLAY 0.617021 (-2910 4010);
PAINT ORANGE (-2910 4010);
FORCEPROP 2 LAST ROOM DDR4_CH_F1
J 0
(-2400 3100);
PAINT ORANGE (-2400 3100);
DISPLAY INVISIBLE (-2400 3100);
FORCEPROP 1 LAST PATH I111
J 0
(-2400 4950);
PAINT GREEN (-2400 4950);
DISPLAY INVISIBLE (-2400 4950);
FORCEPROP 2 LAST CDS_LOCATION J6L1
J 0
(-2850 5000);
DISPLAY 0.617021 (-2850 5000);
PAINT AQUA (-2850 5000);
DISPLAY INVISIBLE (-2850 5000);
FORCEPROP 2 LAST SEC 1
J 0
(-2850 5050);
DISPLAY 0.680851 (-2850 5050);
PAINT MONO (-2850 5050);
DISPLAY INVISIBLE (-2850 5050);
FORCEPROP 2 LAST SEC_TYPE PIP
J 0
(-2850 5050);
DISPLAY 1.021277 (-2850 5050);
PAINT ORANGE (-2850 5050);
DISPLAY INVISIBLE (-2850 5050);
FORCEPROP 2 LAST CDS_LIB mstr_sconn
J 0
(-2400 3100);
PAINT ORANGE (-2400 3100);
DISPLAY INVISIBLE (-2400 3100);
FORCEPROP 2 LAST BOM_COST MEM
J 0
(-2400 3100);
PAINT ORANGE (-2400 3100);
DISPLAY INVISIBLE (-2400 3100);
FORCEPROP 1 LAST PACK_TYPE PIP
J 0
(-2850 5050);
PAINT SKYBLUE (-2850 5050);
DISPLAY INVISIBLE (-2850 5050);
FORCEADD TAP..6
(-3150 4700);
FORCEPROP 3 LASTPIN (-3100 4700) SIG_NAME M_F_MA<16>
J 0
(-3090 4710);
DISPLAY 0.659574 (-3090 4710);
PAINT MONO (-3090 4710);
DISPLAY INVISIBLE (-3090 4710);
FORCEPROP 1 LASTPIN (-3100 4700) BN 16
J 0
(-3150 4710);
DISPLAY 0.617021 (-3150 4710);
PAINT PINK (-3150 4710);
FORCEPROP 1 LAST PATH I112
J 0
(-3150 4700);
DISPLAY 0.936170 (-3150 4700);
PAINT GREEN (-3150 4700);
DISPLAY INVISIBLE (-3150 4700);
FORCEPROP 1 LAST HDL_TAP TRUE
J 0
(-2825 4575);
DISPLAY 1.234043 (-2825 4575);
PAINT GREEN (-2825 4575);
DISPLAY INVISIBLE (-2825 4575);
FORCEPROP 1 LAST BODY_TYPE PLUMBING
J 0
(-3150 4650);
DISPLAY 1.234043 (-3150 4650);
PAINT GREEN (-3150 4650);
DISPLAY INVISIBLE (-3150 4650);
FORCEPROP 2 LAST CDS_LIB mstr_standard
J 2
(-3150 4700);
DISPLAY 0.787234 (-3150 4700);
PAINT MONO (-3150 4700);
DISPLAY INVISIBLE (-3150 4700);
FORCEADD TAP..6
(-3150 4750);
FORCEPROP 3 LASTPIN (-3100 4750) SIG_NAME M_F_MA<17>
J 0
(-3090 4760);
DISPLAY 0.659574 (-3090 4760);
PAINT MONO (-3090 4760);
DISPLAY INVISIBLE (-3090 4760);
FORCEPROP 1 LASTPIN (-3100 4750) BN 17
J 0
(-3150 4760);
DISPLAY 0.617021 (-3150 4760);
PAINT PINK (-3150 4760);
FORCEPROP 1 LAST PATH I113
J 0
(-3150 4750);
DISPLAY 0.936170 (-3150 4750);
PAINT GREEN (-3150 4750);
DISPLAY INVISIBLE (-3150 4750);
FORCEPROP 1 LAST HDL_TAP TRUE
J 0
(-2825 4625);
DISPLAY 1.234043 (-2825 4625);
PAINT GREEN (-2825 4625);
DISPLAY INVISIBLE (-2825 4625);
FORCEPROP 1 LAST BODY_TYPE PLUMBING
J 0
(-3150 4700);
DISPLAY 1.234043 (-3150 4700);
PAINT GREEN (-3150 4700);
DISPLAY INVISIBLE (-3150 4700);
FORCEPROP 2 LAST CDS_LIB mstr_standard
J 0
(-3150 4750);
DISPLAY 0.787234 (-3150 4750);
PAINT MONO (-3150 4750);
DISPLAY INVISIBLE (-3150 4750);
FORCEADD TAP..6
(-3150 4650);
FORCEPROP 3 LASTPIN (-3100 4650) SIG_NAME M_F_MA<15>
J 0
(-3090 4660);
DISPLAY 0.659574 (-3090 4660);
PAINT MONO (-3090 4660);
DISPLAY INVISIBLE (-3090 4660);
FORCEPROP 1 LASTPIN (-3100 4650) BN 15
J 0
(-3150 4660);
DISPLAY 0.617021 (-3150 4660);
PAINT PINK (-3150 4660);
FORCEPROP 1 LAST PATH I114
J 0
(-3150 4650);
DISPLAY 0.936170 (-3150 4650);
PAINT GREEN (-3150 4650);
DISPLAY INVISIBLE (-3150 4650);
FORCEPROP 1 LAST HDL_TAP TRUE
J 0
(-2825 4525);
DISPLAY 1.234043 (-2825 4525);
PAINT GREEN (-2825 4525);
DISPLAY INVISIBLE (-2825 4525);
FORCEPROP 1 LAST BODY_TYPE PLUMBING
J 0
(-3150 4600);
DISPLAY 1.234043 (-3150 4600);
PAINT GREEN (-3150 4600);
DISPLAY INVISIBLE (-3150 4600);
FORCEPROP 2 LAST CDS_LIB mstr_standard
J 2
(-3150 4650);
DISPLAY 0.787234 (-3150 4650);
PAINT MONO (-3150 4650);
DISPLAY INVISIBLE (-3150 4650);
FORCEADD TAP..6
(-3150 4600);
FORCEPROP 3 LASTPIN (-3100 4600) SIG_NAME M_F_MA<14>
J 0
(-3090 4610);
DISPLAY 0.659574 (-3090 4610);
PAINT MONO (-3090 4610);
DISPLAY INVISIBLE (-3090 4610);
FORCEPROP 1 LASTPIN (-3100 4600) BN 14
J 0
(-3150 4610);
DISPLAY 0.617021 (-3150 4610);
PAINT PINK (-3150 4610);
FORCEPROP 1 LAST PATH I115
J 0
(-3150 4600);
DISPLAY 0.936170 (-3150 4600);
PAINT GREEN (-3150 4600);
DISPLAY INVISIBLE (-3150 4600);
FORCEPROP 1 LAST HDL_TAP TRUE
J 0
(-2825 4475);
DISPLAY 1.234043 (-2825 4475);
PAINT GREEN (-2825 4475);
DISPLAY INVISIBLE (-2825 4475);
FORCEPROP 1 LAST BODY_TYPE PLUMBING
J 0
(-3150 4550);
DISPLAY 1.234043 (-3150 4550);
PAINT GREEN (-3150 4550);
DISPLAY INVISIBLE (-3150 4550);
FORCEPROP 2 LAST CDS_LIB mstr_standard
J 2
(-3150 4600);
DISPLAY 0.787234 (-3150 4600);
PAINT MONO (-3150 4600);
DISPLAY INVISIBLE (-3150 4600);
FORCEADD TAP..6
(-3150 4550);
FORCEPROP 3 LASTPIN (-3100 4550) SIG_NAME M_F_MA<13>
J 0
(-3090 4560);
DISPLAY 0.659574 (-3090 4560);
PAINT MONO (-3090 4560);
DISPLAY INVISIBLE (-3090 4560);
FORCEPROP 1 LASTPIN (-3100 4550) BN 13
J 0
(-3150 4560);
DISPLAY 0.617021 (-3150 4560);
PAINT PINK (-3150 4560);
FORCEPROP 1 LAST PATH I116
J 0
(-3150 4550);
DISPLAY 0.936170 (-3150 4550);
PAINT GREEN (-3150 4550);
DISPLAY INVISIBLE (-3150 4550);
FORCEPROP 1 LAST HDL_TAP TRUE
J 0
(-2825 4425);
DISPLAY 1.234043 (-2825 4425);
PAINT GREEN (-2825 4425);
DISPLAY INVISIBLE (-2825 4425);
FORCEPROP 1 LAST BODY_TYPE PLUMBING
J 0
(-3150 4500);
DISPLAY 1.234043 (-3150 4500);
PAINT GREEN (-3150 4500);
DISPLAY INVISIBLE (-3150 4500);
FORCEPROP 2 LAST CDS_LIB mstr_standard
J 2
(-3150 4550);
DISPLAY 0.787234 (-3150 4550);
PAINT MONO (-3150 4550);
DISPLAY INVISIBLE (-3150 4550);
FORCEADD TAP..6
(-3150 4500);
FORCEPROP 3 LASTPIN (-3100 4500) SIG_NAME M_F_MA<12>
J 0
(-3090 4510);
DISPLAY 0.659574 (-3090 4510);
PAINT MONO (-3090 4510);
DISPLAY INVISIBLE (-3090 4510);
FORCEPROP 1 LASTPIN (-3100 4500) BN 12
J 0
(-3150 4510);
DISPLAY 0.617021 (-3150 4510);
PAINT PINK (-3150 4510);
FORCEPROP 1 LAST PATH I117
J 0
(-3150 4500);
DISPLAY 0.936170 (-3150 4500);
PAINT GREEN (-3150 4500);
DISPLAY INVISIBLE (-3150 4500);
FORCEPROP 1 LAST HDL_TAP TRUE
J 0
(-2825 4375);
DISPLAY 1.234043 (-2825 4375);
PAINT GREEN (-2825 4375);
DISPLAY INVISIBLE (-2825 4375);
FORCEPROP 1 LAST BODY_TYPE PLUMBING
J 0
(-3150 4450);
DISPLAY 1.234043 (-3150 4450);
PAINT GREEN (-3150 4450);
DISPLAY INVISIBLE (-3150 4450);
FORCEPROP 2 LAST CDS_LIB mstr_standard
J 2
(-3150 4500);
DISPLAY 0.787234 (-3150 4500);
PAINT MONO (-3150 4500);
DISPLAY INVISIBLE (-3150 4500);
FORCEADD TAP..6
(-3150 4450);
FORCEPROP 3 LASTPIN (-3100 4450) SIG_NAME M_F_MA<11>
J 0
(-3090 4460);
DISPLAY 0.659574 (-3090 4460);
PAINT MONO (-3090 4460);
DISPLAY INVISIBLE (-3090 4460);
FORCEPROP 1 LASTPIN (-3100 4450) BN 11
J 0
(-3150 4460);
DISPLAY 0.617021 (-3150 4460);
PAINT PINK (-3150 4460);
FORCEPROP 1 LAST PATH I118
J 0
(-3150 4450);
DISPLAY 0.936170 (-3150 4450);
PAINT GREEN (-3150 4450);
DISPLAY INVISIBLE (-3150 4450);
FORCEPROP 1 LAST HDL_TAP TRUE
J 0
(-2825 4325);
DISPLAY 1.234043 (-2825 4325);
PAINT GREEN (-2825 4325);
DISPLAY INVISIBLE (-2825 4325);
FORCEPROP 1 LAST BODY_TYPE PLUMBING
J 0
(-3150 4400);
DISPLAY 1.234043 (-3150 4400);
PAINT GREEN (-3150 4400);
DISPLAY INVISIBLE (-3150 4400);
FORCEPROP 2 LAST CDS_LIB mstr_standard
J 2
(-3150 4450);
DISPLAY 0.787234 (-3150 4450);
PAINT MONO (-3150 4450);
DISPLAY INVISIBLE (-3150 4450);
FORCEADD TAP..6
(-3150 4400);
FORCEPROP 3 LASTPIN (-3100 4400) SIG_NAME M_F_MA<10>
J 0
(-3090 4410);
DISPLAY 0.659574 (-3090 4410);
PAINT MONO (-3090 4410);
DISPLAY INVISIBLE (-3090 4410);
FORCEPROP 1 LASTPIN (-3100 4400) BN 10
J 0
(-3150 4410);
DISPLAY 0.617021 (-3150 4410);
PAINT PINK (-3150 4410);
FORCEPROP 1 LAST PATH I119
J 0
(-3150 4400);
DISPLAY 0.936170 (-3150 4400);
PAINT GREEN (-3150 4400);
DISPLAY INVISIBLE (-3150 4400);
FORCEPROP 1 LAST HDL_TAP TRUE
J 0
(-2825 4275);
DISPLAY 1.234043 (-2825 4275);
PAINT GREEN (-2825 4275);
DISPLAY INVISIBLE (-2825 4275);
FORCEPROP 1 LAST BODY_TYPE PLUMBING
J 0
(-3150 4350);
DISPLAY 1.234043 (-3150 4350);
PAINT GREEN (-3150 4350);
DISPLAY INVISIBLE (-3150 4350);
FORCEPROP 2 LAST CDS_LIB mstr_standard
J 2
(-3150 4400);
DISPLAY 0.787234 (-3150 4400);
PAINT MONO (-3150 4400);
DISPLAY INVISIBLE (-3150 4400);
FORCEADD TAP..6
R 2
(700 5050);
FORCEPROP 3 LASTPIN (650 5050) SIG_NAME M_F_DQS_DP<16>
J 0
(660 5060);
DISPLAY 0.659574 (660 5060);
PAINT MONO (660 5060);
DISPLAY INVISIBLE (660 5060);
FORCEPROP 1 LASTPIN (650 5050) BN 16
J 2
(700 5060);
DISPLAY 0.617021 (700 5060);
PAINT PINK (700 5060);
FORCEPROP 1 LAST PATH I12
J 2
(700 5050);
DISPLAY 0.936170 (700 5050);
PAINT GREEN (700 5050);
DISPLAY INVISIBLE (700 5050);
FORCEPROP 1 LAST HDL_TAP TRUE
J 2
(375 4925);
DISPLAY 1.234043 (375 4925);
PAINT GREEN (375 4925);
DISPLAY INVISIBLE (375 4925);
FORCEPROP 1 LAST BODY_TYPE PLUMBING
J 2
(700 5000);
DISPLAY 1.234043 (700 5000);
PAINT GREEN (700 5000);
DISPLAY INVISIBLE (700 5000);
FORCEPROP 2 LAST CDS_LIB mstr_standard
J 0
(700 5050);
DISPLAY 0.787234 (700 5050);
PAINT MONO (700 5050);
DISPLAY INVISIBLE (700 5050);
FORCEADD TAP..6
(-3150 4350);
FORCEPROP 3 LASTPIN (-3100 4350) SIG_NAME M_F_MA<9>
J 0
(-3090 4360);
DISPLAY 0.659574 (-3090 4360);
PAINT MONO (-3090 4360);
DISPLAY INVISIBLE (-3090 4360);
FORCEPROP 1 LASTPIN (-3100 4350) BN 9
J 0
(-3150 4360);
DISPLAY 0.617021 (-3150 4360);
PAINT PINK (-3150 4360);
FORCEPROP 1 LAST PATH I120
J 0
(-3150 4350);
DISPLAY 0.936170 (-3150 4350);
PAINT GREEN (-3150 4350);
DISPLAY INVISIBLE (-3150 4350);
FORCEPROP 1 LAST HDL_TAP TRUE
J 0
(-2825 4225);
DISPLAY 1.234043 (-2825 4225);
PAINT GREEN (-2825 4225);
DISPLAY INVISIBLE (-2825 4225);
FORCEPROP 1 LAST BODY_TYPE PLUMBING
J 0
(-3150 4300);
DISPLAY 1.234043 (-3150 4300);
PAINT GREEN (-3150 4300);
DISPLAY INVISIBLE (-3150 4300);
FORCEPROP 2 LAST CDS_LIB mstr_standard
J 2
(-3150 4350);
DISPLAY 0.787234 (-3150 4350);
PAINT MONO (-3150 4350);
DISPLAY INVISIBLE (-3150 4350);
FORCEADD TAP..6
(-3150 4300);
FORCEPROP 3 LASTPIN (-3100 4300) SIG_NAME M_F_MA<8>
J 0
(-3090 4310);
DISPLAY 0.659574 (-3090 4310);
PAINT MONO (-3090 4310);
DISPLAY INVISIBLE (-3090 4310);
FORCEPROP 1 LASTPIN (-3100 4300) BN 8
J 0
(-3150 4310);
DISPLAY 0.617021 (-3150 4310);
PAINT PINK (-3150 4310);
FORCEPROP 1 LAST PATH I121
J 0
(-3150 4300);
DISPLAY 0.936170 (-3150 4300);
PAINT GREEN (-3150 4300);
DISPLAY INVISIBLE (-3150 4300);
FORCEPROP 1 LAST HDL_TAP TRUE
J 0
(-2825 4175);
DISPLAY 1.234043 (-2825 4175);
PAINT GREEN (-2825 4175);
DISPLAY INVISIBLE (-2825 4175);
FORCEPROP 1 LAST BODY_TYPE PLUMBING
J 0
(-3150 4250);
DISPLAY 1.234043 (-3150 4250);
PAINT GREEN (-3150 4250);
DISPLAY INVISIBLE (-3150 4250);
FORCEPROP 2 LAST CDS_LIB mstr_standard
J 2
(-3150 4300);
DISPLAY 0.787234 (-3150 4300);
PAINT MONO (-3150 4300);
DISPLAY INVISIBLE (-3150 4300);
FORCEADD TAP..6
(-3150 4250);
FORCEPROP 3 LASTPIN (-3100 4250) SIG_NAME M_F_MA<7>
J 0
(-3090 4260);
DISPLAY 0.659574 (-3090 4260);
PAINT MONO (-3090 4260);
DISPLAY INVISIBLE (-3090 4260);
FORCEPROP 1 LASTPIN (-3100 4250) BN 7
J 0
(-3150 4260);
DISPLAY 0.617021 (-3150 4260);
PAINT PINK (-3150 4260);
FORCEPROP 1 LAST PATH I122
J 0
(-3150 4250);
DISPLAY 0.936170 (-3150 4250);
PAINT GREEN (-3150 4250);
DISPLAY INVISIBLE (-3150 4250);
FORCEPROP 1 LAST HDL_TAP TRUE
J 0
(-2825 4125);
DISPLAY 1.234043 (-2825 4125);
PAINT GREEN (-2825 4125);
DISPLAY INVISIBLE (-2825 4125);
FORCEPROP 1 LAST BODY_TYPE PLUMBING
J 0
(-3150 4200);
DISPLAY 1.234043 (-3150 4200);
PAINT GREEN (-3150 4200);
DISPLAY INVISIBLE (-3150 4200);
FORCEPROP 2 LAST CDS_LIB mstr_standard
J 2
(-3150 4250);
DISPLAY 0.787234 (-3150 4250);
PAINT MONO (-3150 4250);
DISPLAY INVISIBLE (-3150 4250);
FORCEADD TAP..6
(-3150 4200);
FORCEPROP 3 LASTPIN (-3100 4200) SIG_NAME M_F_MA<6>
J 0
(-3090 4210);
DISPLAY 0.659574 (-3090 4210);
PAINT MONO (-3090 4210);
DISPLAY INVISIBLE (-3090 4210);
FORCEPROP 1 LASTPIN (-3100 4200) BN 6
J 0
(-3150 4210);
DISPLAY 0.617021 (-3150 4210);
PAINT PINK (-3150 4210);
FORCEPROP 1 LAST PATH I123
J 0
(-3150 4200);
DISPLAY 0.936170 (-3150 4200);
PAINT GREEN (-3150 4200);
DISPLAY INVISIBLE (-3150 4200);
FORCEPROP 1 LAST HDL_TAP TRUE
J 0
(-2825 4075);
DISPLAY 1.234043 (-2825 4075);
PAINT GREEN (-2825 4075);
DISPLAY INVISIBLE (-2825 4075);
FORCEPROP 1 LAST BODY_TYPE PLUMBING
J 0
(-3150 4150);
DISPLAY 1.234043 (-3150 4150);
PAINT GREEN (-3150 4150);
DISPLAY INVISIBLE (-3150 4150);
FORCEPROP 2 LAST CDS_LIB mstr_standard
J 2
(-3150 4200);
DISPLAY 0.787234 (-3150 4200);
PAINT MONO (-3150 4200);
DISPLAY INVISIBLE (-3150 4200);
FORCEADD TAP..6
(-3150 4150);
FORCEPROP 3 LASTPIN (-3100 4150) SIG_NAME M_F_MA<5>
J 0
(-3090 4160);
DISPLAY 0.659574 (-3090 4160);
PAINT MONO (-3090 4160);
DISPLAY INVISIBLE (-3090 4160);
FORCEPROP 1 LASTPIN (-3100 4150) BN 5
J 0
(-3150 4160);
DISPLAY 0.617021 (-3150 4160);
PAINT PINK (-3150 4160);
FORCEPROP 1 LAST PATH I124
J 0
(-3150 4150);
DISPLAY 0.936170 (-3150 4150);
PAINT GREEN (-3150 4150);
DISPLAY INVISIBLE (-3150 4150);
FORCEPROP 1 LAST HDL_TAP TRUE
J 0
(-2825 4025);
DISPLAY 1.234043 (-2825 4025);
PAINT GREEN (-2825 4025);
DISPLAY INVISIBLE (-2825 4025);
FORCEPROP 1 LAST BODY_TYPE PLUMBING
J 0
(-3150 4100);
DISPLAY 1.234043 (-3150 4100);
PAINT GREEN (-3150 4100);
DISPLAY INVISIBLE (-3150 4100);
FORCEPROP 2 LAST CDS_LIB mstr_standard
J 2
(-3150 4150);
DISPLAY 0.787234 (-3150 4150);
PAINT MONO (-3150 4150);
DISPLAY INVISIBLE (-3150 4150);
FORCEADD TAP..6
(-3150 4100);
FORCEPROP 3 LASTPIN (-3100 4100) SIG_NAME M_F_MA<4>
J 0
(-3090 4110);
DISPLAY 0.659574 (-3090 4110);
PAINT MONO (-3090 4110);
DISPLAY INVISIBLE (-3090 4110);
FORCEPROP 1 LASTPIN (-3100 4100) BN 4
J 0
(-3150 4110);
DISPLAY 0.617021 (-3150 4110);
PAINT PINK (-3150 4110);
FORCEPROP 1 LAST PATH I125
J 0
(-3150 4100);
DISPLAY 0.936170 (-3150 4100);
PAINT GREEN (-3150 4100);
DISPLAY INVISIBLE (-3150 4100);
FORCEPROP 1 LAST HDL_TAP TRUE
J 0
(-2825 3975);
DISPLAY 1.234043 (-2825 3975);
PAINT GREEN (-2825 3975);
DISPLAY INVISIBLE (-2825 3975);
FORCEPROP 1 LAST BODY_TYPE PLUMBING
J 0
(-3150 4050);
DISPLAY 1.234043 (-3150 4050);
PAINT GREEN (-3150 4050);
DISPLAY INVISIBLE (-3150 4050);
FORCEPROP 2 LAST CDS_LIB mstr_standard
J 2
(-3150 4100);
DISPLAY 0.787234 (-3150 4100);
PAINT MONO (-3150 4100);
DISPLAY INVISIBLE (-3150 4100);
FORCEADD TAP..6
(-3150 4000);
FORCEPROP 3 LASTPIN (-3100 4000) SIG_NAME M_F_MA<2>
J 0
(-3090 4010);
DISPLAY 0.659574 (-3090 4010);
PAINT MONO (-3090 4010);
DISPLAY INVISIBLE (-3090 4010);
FORCEPROP 1 LASTPIN (-3100 4000) BN 2
J 0
(-3150 4010);
DISPLAY 0.617021 (-3150 4010);
PAINT PINK (-3150 4010);
FORCEPROP 1 LAST PATH I126
J 0
(-3150 4000);
DISPLAY 0.936170 (-3150 4000);
PAINT GREEN (-3150 4000);
DISPLAY INVISIBLE (-3150 4000);
FORCEPROP 1 LAST HDL_TAP TRUE
J 0
(-2825 3875);
DISPLAY 1.234043 (-2825 3875);
PAINT GREEN (-2825 3875);
DISPLAY INVISIBLE (-2825 3875);
FORCEPROP 1 LAST BODY_TYPE PLUMBING
J 0
(-3150 3950);
DISPLAY 1.234043 (-3150 3950);
PAINT GREEN (-3150 3950);
DISPLAY INVISIBLE (-3150 3950);
FORCEPROP 2 LAST CDS_LIB mstr_standard
J 2
(-3150 4000);
DISPLAY 0.787234 (-3150 4000);
PAINT MONO (-3150 4000);
DISPLAY INVISIBLE (-3150 4000);
FORCEADD TAP..6
(-3150 4050);
FORCEPROP 3 LASTPIN (-3100 4050) SIG_NAME M_F_MA<3>
J 0
(-3090 4060);
DISPLAY 0.659574 (-3090 4060);
PAINT MONO (-3090 4060);
DISPLAY INVISIBLE (-3090 4060);
FORCEPROP 1 LASTPIN (-3100 4050) BN 3
J 0
(-3150 4060);
DISPLAY 0.617021 (-3150 4060);
PAINT PINK (-3150 4060);
FORCEPROP 1 LAST PATH I127
J 0
(-3150 4050);
DISPLAY 0.936170 (-3150 4050);
PAINT GREEN (-3150 4050);
DISPLAY INVISIBLE (-3150 4050);
FORCEPROP 1 LAST HDL_TAP TRUE
J 0
(-2825 3925);
DISPLAY 1.234043 (-2825 3925);
PAINT GREEN (-2825 3925);
DISPLAY INVISIBLE (-2825 3925);
FORCEPROP 1 LAST BODY_TYPE PLUMBING
J 0
(-3150 4000);
DISPLAY 1.234043 (-3150 4000);
PAINT GREEN (-3150 4000);
DISPLAY INVISIBLE (-3150 4000);
FORCEPROP 2 LAST CDS_LIB mstr_standard
J 2
(-3150 4050);
DISPLAY 0.787234 (-3150 4050);
PAINT MONO (-3150 4050);
DISPLAY INVISIBLE (-3150 4050);
FORCEADD TAP..6
(-3150 3950);
FORCEPROP 3 LASTPIN (-3100 3950) SIG_NAME M_F_MA<1>
J 0
(-3090 3960);
DISPLAY 0.659574 (-3090 3960);
PAINT MONO (-3090 3960);
DISPLAY INVISIBLE (-3090 3960);
FORCEPROP 1 LASTPIN (-3100 3950) BN 1
J 0
(-3150 3960);
DISPLAY 0.617021 (-3150 3960);
PAINT PINK (-3150 3960);
FORCEPROP 1 LAST PATH I128
J 0
(-3150 3950);
DISPLAY 0.936170 (-3150 3950);
PAINT GREEN (-3150 3950);
DISPLAY INVISIBLE (-3150 3950);
FORCEPROP 1 LAST HDL_TAP TRUE
J 0
(-2825 3825);
DISPLAY 1.234043 (-2825 3825);
PAINT GREEN (-2825 3825);
DISPLAY INVISIBLE (-2825 3825);
FORCEPROP 1 LAST BODY_TYPE PLUMBING
J 0
(-3150 3900);
DISPLAY 1.234043 (-3150 3900);
PAINT GREEN (-3150 3900);
DISPLAY INVISIBLE (-3150 3900);
FORCEPROP 2 LAST CDS_LIB mstr_standard
J 2
(-3150 3950);
DISPLAY 0.787234 (-3150 3950);
PAINT MONO (-3150 3950);
DISPLAY INVISIBLE (-3150 3950);
FORCEADD TAP..6
(-3150 3900);
FORCEPROP 3 LASTPIN (-3100 3900) SIG_NAME M_F_MA<0>
J 0
(-3090 3910);
DISPLAY 0.659574 (-3090 3910);
PAINT MONO (-3090 3910);
DISPLAY INVISIBLE (-3090 3910);
FORCEPROP 1 LASTPIN (-3100 3900) BN 0
J 0
(-3150 3910);
DISPLAY 0.617021 (-3150 3910);
PAINT PINK (-3150 3910);
FORCEPROP 1 LAST PATH I129
J 0
(-3150 3900);
DISPLAY 0.936170 (-3150 3900);
PAINT GREEN (-3150 3900);
DISPLAY INVISIBLE (-3150 3900);
FORCEPROP 1 LAST HDL_TAP TRUE
J 0
(-2825 3775);
DISPLAY 1.234043 (-2825 3775);
PAINT GREEN (-2825 3775);
DISPLAY INVISIBLE (-2825 3775);
FORCEPROP 1 LAST BODY_TYPE PLUMBING
J 0
(-3150 3850);
DISPLAY 1.234043 (-3150 3850);
PAINT GREEN (-3150 3850);
DISPLAY INVISIBLE (-3150 3850);
FORCEPROP 2 LAST CDS_LIB mstr_standard
J 2
(-3150 3900);
DISPLAY 0.787234 (-3150 3900);
PAINT MONO (-3150 3900);
DISPLAY INVISIBLE (-3150 3900);
FORCEADD TAP..6
R 2
(700 4550);
FORCEPROP 3 LASTPIN (650 4550) SIG_NAME M_F_DQS_DP<11>
J 0
(660 4560);
DISPLAY 0.659574 (660 4560);
PAINT MONO (660 4560);
DISPLAY INVISIBLE (660 4560);
FORCEPROP 1 LASTPIN (650 4550) BN 11
J 2
(700 4560);
DISPLAY 0.617021 (700 4560);
PAINT PINK (700 4560);
FORCEPROP 1 LAST PATH I13
J 2
(700 4550);
DISPLAY 0.936170 (700 4550);
PAINT GREEN (700 4550);
DISPLAY INVISIBLE (700 4550);
FORCEPROP 1 LAST HDL_TAP TRUE
J 2
(375 4425);
DISPLAY 1.234043 (375 4425);
PAINT GREEN (375 4425);
DISPLAY INVISIBLE (375 4425);
FORCEPROP 1 LAST BODY_TYPE PLUMBING
J 2
(700 4500);
DISPLAY 1.234043 (700 4500);
PAINT GREEN (700 4500);
DISPLAY INVISIBLE (700 4500);
FORCEPROP 2 LAST CDS_LIB mstr_standard
J 0
(700 4550);
DISPLAY 0.787234 (700 4550);
PAINT MONO (700 4550);
DISPLAY INVISIBLE (700 4550);
FORCEADD TAP..6
(-3150 3800);
FORCEPROP 3 LASTPIN (-3100 3800) SIG_NAME M_F_BA<1>
J 0
(-3090 3810);
DISPLAY 0.659574 (-3090 3810);
PAINT MONO (-3090 3810);
DISPLAY INVISIBLE (-3090 3810);
FORCEPROP 1 LASTPIN (-3100 3800) BN 1
J 0
(-3150 3810);
DISPLAY 0.617021 (-3150 3810);
PAINT PINK (-3150 3810);
FORCEPROP 1 LAST PATH I130
J 0
(-3150 3800);
DISPLAY 0.936170 (-3150 3800);
PAINT GREEN (-3150 3800);
DISPLAY INVISIBLE (-3150 3800);
FORCEPROP 1 LAST HDL_TAP TRUE
J 0
(-2825 3675);
DISPLAY 1.234043 (-2825 3675);
PAINT GREEN (-2825 3675);
DISPLAY INVISIBLE (-2825 3675);
FORCEPROP 1 LAST BODY_TYPE PLUMBING
J 0
(-3150 3750);
DISPLAY 1.234043 (-3150 3750);
PAINT GREEN (-3150 3750);
DISPLAY INVISIBLE (-3150 3750);
FORCEPROP 2 LAST CDS_LIB mstr_standard
J 0
(-3150 3800);
DISPLAY 0.787234 (-3150 3800);
PAINT MONO (-3150 3800);
DISPLAY INVISIBLE (-3150 3800);
FORCEADD OFFPAGE..1
(-3775 4800);
FORCEPROP 2 LAST $XR1 53 
J 0
(-4086 4800);
DISPLAY 0.638298 (-4086 4800);
PAINT MONO (-4086 4800);
FORCEPROP 2 LAST $XR0 28 
J 0
(-3996 4800);
DISPLAY 0.638298 (-3996 4800);
PAINT MONO (-3996 4800);
FORCEPROP 2 LAST PATH I131
J 0
(-3725 4875);
DISPLAY 0.787234 (-3725 4875);
PAINT MONO (-3725 4875);
DISPLAY INVISIBLE (-3725 4875);
FORCEPROP 1 LAST COMMENT_BODY TRUE
J 0
(-3650 4700);
DISPLAY 0.936170 (-3650 4700);
PAINT GREEN (-3650 4700);
DISPLAY INVISIBLE (-3650 4700);
FORCEPROP 1 LAST OFFPAGE TRUE
J 0
(-3450 4675);
DISPLAY 0.936170 (-3450 4675);
PAINT GREEN (-3450 4675);
DISPLAY INVISIBLE (-3450 4675);
FORCEPROP 2 LAST CDS_LIB mstr_standard
J 0
(-3775 4800);
DISPLAY 0.787234 (-3775 4800);
PAINT MONO (-3775 4800);
DISPLAY INVISIBLE (-3775 4800);
FORCEADD OFFPAGE..1
(-3800 3900);
FORCEPROP 2 LAST $XR1 53 
J 0
(-4141 3900);
DISPLAY 0.638298 (-4141 3900);
PAINT MONO (-4141 3900);
FORCEPROP 2 LAST $XR0 28 
J 0
(-4051 3900);
DISPLAY 0.638298 (-4051 3900);
PAINT MONO (-4051 3900);
FORCEPROP 2 LAST PATH I132
J 0
(-3750 3975);
DISPLAY 0.787234 (-3750 3975);
PAINT MONO (-3750 3975);
DISPLAY INVISIBLE (-3750 3975);
FORCEPROP 1 LAST COMMENT_BODY TRUE
J 0
(-3675 3800);
DISPLAY 0.936170 (-3675 3800);
PAINT GREEN (-3675 3800);
DISPLAY INVISIBLE (-3675 3800);
FORCEPROP 1 LAST OFFPAGE TRUE
J 0
(-3475 3775);
DISPLAY 0.936170 (-3475 3775);
PAINT GREEN (-3475 3775);
DISPLAY INVISIBLE (-3475 3775);
FORCEPROP 2 LAST CDS_LIB mstr_standard
J 0
(-3800 3900);
DISPLAY 0.787234 (-3800 3900);
PAINT MONO (-3800 3900);
DISPLAY INVISIBLE (-3800 3900);
FORCEADD TAP..6
(-3150 3750);
FORCEPROP 3 LASTPIN (-3100 3750) SIG_NAME M_F_BA<0>
J 0
(-3090 3760);
DISPLAY 0.659574 (-3090 3760);
PAINT MONO (-3090 3760);
DISPLAY INVISIBLE (-3090 3760);
FORCEPROP 1 LASTPIN (-3100 3750) BN 0
J 0
(-3150 3760);
DISPLAY 0.617021 (-3150 3760);
PAINT PINK (-3150 3760);
FORCEPROP 1 LAST PATH I133
J 0
(-3150 3750);
DISPLAY 0.936170 (-3150 3750);
PAINT GREEN (-3150 3750);
DISPLAY INVISIBLE (-3150 3750);
FORCEPROP 1 LAST HDL_TAP TRUE
J 0
(-2825 3625);
DISPLAY 1.234043 (-2825 3625);
PAINT GREEN (-2825 3625);
DISPLAY INVISIBLE (-2825 3625);
FORCEPROP 1 LAST BODY_TYPE PLUMBING
J 0
(-3150 3700);
DISPLAY 1.234043 (-3150 3700);
PAINT GREEN (-3150 3700);
DISPLAY INVISIBLE (-3150 3700);
FORCEPROP 2 LAST CDS_LIB mstr_standard
J 0
(-3150 3750);
DISPLAY 0.787234 (-3150 3750);
PAINT MONO (-3150 3750);
DISPLAY INVISIBLE (-3150 3750);
FORCEADD TAP..6
(-3150 3700);
FORCEPROP 3 LASTPIN (-3100 3700) SIG_NAME M_F_BG<1>
J 0
(-3090 3710);
DISPLAY 0.659574 (-3090 3710);
PAINT MONO (-3090 3710);
DISPLAY INVISIBLE (-3090 3710);
FORCEPROP 1 LASTPIN (-3100 3700) BN 1
J 0
(-3150 3710);
DISPLAY 0.617021 (-3150 3710);
PAINT PINK (-3150 3710);
FORCEPROP 1 LAST PATH I134
J 0
(-3150 3700);
DISPLAY 0.936170 (-3150 3700);
PAINT GREEN (-3150 3700);
DISPLAY INVISIBLE (-3150 3700);
FORCEPROP 1 LAST HDL_TAP TRUE
J 0
(-2825 3575);
DISPLAY 1.234043 (-2825 3575);
PAINT GREEN (-2825 3575);
DISPLAY INVISIBLE (-2825 3575);
FORCEPROP 1 LAST BODY_TYPE PLUMBING
J 0
(-3150 3650);
DISPLAY 1.234043 (-3150 3650);
PAINT GREEN (-3150 3650);
DISPLAY INVISIBLE (-3150 3650);
FORCEPROP 2 LAST CDS_LIB mstr_standard
J 0
(-3150 3700);
DISPLAY 0.787234 (-3150 3700);
PAINT MONO (-3150 3700);
DISPLAY INVISIBLE (-3150 3700);
FORCEADD TAP..6
(-3150 3650);
FORCEPROP 3 LASTPIN (-3100 3650) SIG_NAME M_F_BG<0>
J 0
(-3090 3660);
DISPLAY 0.659574 (-3090 3660);
PAINT MONO (-3090 3660);
DISPLAY INVISIBLE (-3090 3660);
FORCEPROP 1 LASTPIN (-3100 3650) BN 0
J 0
(-3150 3660);
DISPLAY 0.617021 (-3150 3660);
PAINT PINK (-3150 3660);
FORCEPROP 1 LAST PATH I135
J 0
(-3150 3650);
DISPLAY 0.936170 (-3150 3650);
PAINT GREEN (-3150 3650);
DISPLAY INVISIBLE (-3150 3650);
FORCEPROP 1 LAST HDL_TAP TRUE
J 0
(-2825 3525);
DISPLAY 1.234043 (-2825 3525);
PAINT GREEN (-2825 3525);
DISPLAY INVISIBLE (-2825 3525);
FORCEPROP 1 LAST BODY_TYPE PLUMBING
J 0
(-3150 3600);
DISPLAY 1.234043 (-3150 3600);
PAINT GREEN (-3150 3600);
DISPLAY INVISIBLE (-3150 3600);
FORCEPROP 2 LAST CDS_LIB mstr_standard
J 0
(-3150 3650);
DISPLAY 0.787234 (-3150 3650);
PAINT MONO (-3150 3650);
DISPLAY INVISIBLE (-3150 3650);
FORCEADD OFFPAGE..1
(-3800 3350);
FORCEPROP 2 LAST $XR1 53 
J 0
(-4141 3350);
DISPLAY 0.638298 (-4141 3350);
PAINT MONO (-4141 3350);
FORCEPROP 2 LAST $XR0 28 
J 0
(-4051 3350);
DISPLAY 0.638298 (-4051 3350);
PAINT MONO (-4051 3350);
FORCEPROP 2 LAST PATH I136
J 0
(-3750 3425);
DISPLAY 0.787234 (-3750 3425);
PAINT MONO (-3750 3425);
DISPLAY INVISIBLE (-3750 3425);
FORCEPROP 1 LAST COMMENT_BODY TRUE
J 0
(-3675 3250);
DISPLAY 0.936170 (-3675 3250);
PAINT GREEN (-3675 3250);
DISPLAY INVISIBLE (-3675 3250);
FORCEPROP 1 LAST OFFPAGE TRUE
J 0
(-3475 3225);
DISPLAY 0.936170 (-3475 3225);
PAINT GREEN (-3475 3225);
DISPLAY INVISIBLE (-3475 3225);
FORCEPROP 2 LAST CDS_LIB mstr_standard
J 0
(-3800 3350);
DISPLAY 0.787234 (-3800 3350);
PAINT MONO (-3800 3350);
DISPLAY INVISIBLE (-3800 3350);
FORCEADD OFFPAGE..1
(-3800 3750);
FORCEPROP 2 LAST $XR1 53 
J 0
(-4141 3750);
DISPLAY 0.638298 (-4141 3750);
PAINT MONO (-4141 3750);
FORCEPROP 2 LAST $XR0 28 
J 0
(-4051 3750);
DISPLAY 0.638298 (-4051 3750);
PAINT MONO (-4051 3750);
FORCEPROP 2 LAST PATH I137
J 0
(-3750 3825);
DISPLAY 0.787234 (-3750 3825);
PAINT MONO (-3750 3825);
DISPLAY INVISIBLE (-3750 3825);
FORCEPROP 1 LAST COMMENT_BODY TRUE
J 0
(-3675 3650);
DISPLAY 0.936170 (-3675 3650);
PAINT GREEN (-3675 3650);
DISPLAY INVISIBLE (-3675 3650);
FORCEPROP 1 LAST OFFPAGE TRUE
J 0
(-3475 3625);
DISPLAY 0.936170 (-3475 3625);
PAINT GREEN (-3475 3625);
DISPLAY INVISIBLE (-3475 3625);
FORCEPROP 2 LAST CDS_LIB mstr_standard
J 0
(-3800 3750);
DISPLAY 0.787234 (-3800 3750);
PAINT MONO (-3800 3750);
DISPLAY INVISIBLE (-3800 3750);
FORCEADD TAP..6
(-3150 2700);
FORCEPROP 3 LASTPIN (-3100 2700) SIG_NAME M_F_ECC<7>
J 0
(-3090 2710);
DISPLAY 0.659574 (-3090 2710);
PAINT MONO (-3090 2710);
DISPLAY INVISIBLE (-3090 2710);
FORCEPROP 1 LASTPIN (-3100 2700) BN 7
J 0
(-3150 2710);
DISPLAY 0.617021 (-3150 2710);
PAINT PINK (-3150 2710);
FORCEPROP 1 LAST PATH I138
J 0
(-3150 2700);
DISPLAY 0.936170 (-3150 2700);
PAINT GREEN (-3150 2700);
DISPLAY INVISIBLE (-3150 2700);
FORCEPROP 1 LAST HDL_TAP TRUE
J 0
(-2825 2575);
DISPLAY 1.234043 (-2825 2575);
PAINT GREEN (-2825 2575);
DISPLAY INVISIBLE (-2825 2575);
FORCEPROP 1 LAST BODY_TYPE PLUMBING
J 0
(-3150 2650);
DISPLAY 1.234043 (-3150 2650);
PAINT GREEN (-3150 2650);
DISPLAY INVISIBLE (-3150 2650);
FORCEPROP 2 LAST CDS_LIB mstr_standard
J 0
(-3150 2700);
DISPLAY 0.787234 (-3150 2700);
PAINT MONO (-3150 2700);
DISPLAY INVISIBLE (-3150 2700);
FORCEADD TAP..6
(-3150 2650);
FORCEPROP 3 LASTPIN (-3100 2650) SIG_NAME M_F_ECC<6>
J 0
(-3090 2660);
DISPLAY 0.659574 (-3090 2660);
PAINT MONO (-3090 2660);
DISPLAY INVISIBLE (-3090 2660);
FORCEPROP 1 LASTPIN (-3100 2650) BN 6
J 0
(-3150 2660);
DISPLAY 0.617021 (-3150 2660);
PAINT PINK (-3150 2660);
FORCEPROP 1 LAST PATH I139
J 0
(-3150 2650);
DISPLAY 0.936170 (-3150 2650);
PAINT GREEN (-3150 2650);
DISPLAY INVISIBLE (-3150 2650);
FORCEPROP 1 LAST HDL_TAP TRUE
J 0
(-2825 2525);
DISPLAY 1.234043 (-2825 2525);
PAINT GREEN (-2825 2525);
DISPLAY INVISIBLE (-2825 2525);
FORCEPROP 1 LAST BODY_TYPE PLUMBING
J 0
(-3150 2600);
DISPLAY 1.234043 (-3150 2600);
PAINT GREEN (-3150 2600);
DISPLAY INVISIBLE (-3150 2600);
FORCEPROP 2 LAST CDS_LIB mstr_standard
J 0
(-3150 2650);
DISPLAY 0.787234 (-3150 2650);
PAINT MONO (-3150 2650);
DISPLAY INVISIBLE (-3150 2650);
FORCEADD TAP..6
R 2
(700 4650);
FORCEPROP 3 LASTPIN (650 4650) SIG_NAME M_F_DQS_DP<12>
J 0
(660 4660);
DISPLAY 0.659574 (660 4660);
PAINT MONO (660 4660);
DISPLAY INVISIBLE (660 4660);
FORCEPROP 1 LASTPIN (650 4650) BN 12
J 2
(700 4660);
DISPLAY 0.617021 (700 4660);
PAINT PINK (700 4660);
FORCEPROP 1 LAST PATH I14
J 2
(700 4650);
DISPLAY 0.936170 (700 4650);
PAINT GREEN (700 4650);
DISPLAY INVISIBLE (700 4650);
FORCEPROP 1 LAST HDL_TAP TRUE
J 2
(375 4525);
DISPLAY 1.234043 (375 4525);
PAINT GREEN (375 4525);
DISPLAY INVISIBLE (375 4525);
FORCEPROP 1 LAST BODY_TYPE PLUMBING
J 2
(700 4600);
DISPLAY 1.234043 (700 4600);
PAINT GREEN (700 4600);
DISPLAY INVISIBLE (700 4600);
FORCEPROP 2 LAST CDS_LIB mstr_standard
J 0
(700 4650);
DISPLAY 0.787234 (700 4650);
PAINT MONO (700 4650);
DISPLAY INVISIBLE (700 4650);
FORCEADD TAP..6
(-3150 2600);
FORCEPROP 3 LASTPIN (-3100 2600) SIG_NAME M_F_ECC<5>
J 0
(-3090 2610);
DISPLAY 0.659574 (-3090 2610);
PAINT MONO (-3090 2610);
DISPLAY INVISIBLE (-3090 2610);
FORCEPROP 1 LASTPIN (-3100 2600) BN 5
J 0
(-3150 2610);
DISPLAY 0.617021 (-3150 2610);
PAINT PINK (-3150 2610);
FORCEPROP 1 LAST PATH I140
J 0
(-3150 2600);
DISPLAY 0.936170 (-3150 2600);
PAINT GREEN (-3150 2600);
DISPLAY INVISIBLE (-3150 2600);
FORCEPROP 1 LAST HDL_TAP TRUE
J 0
(-2825 2475);
DISPLAY 1.234043 (-2825 2475);
PAINT GREEN (-2825 2475);
DISPLAY INVISIBLE (-2825 2475);
FORCEPROP 1 LAST BODY_TYPE PLUMBING
J 0
(-3150 2550);
DISPLAY 1.234043 (-3150 2550);
PAINT GREEN (-3150 2550);
DISPLAY INVISIBLE (-3150 2550);
FORCEPROP 2 LAST CDS_LIB mstr_standard
J 0
(-3150 2600);
DISPLAY 0.787234 (-3150 2600);
PAINT MONO (-3150 2600);
DISPLAY INVISIBLE (-3150 2600);
FORCEADD TAP..6
(-3150 2550);
FORCEPROP 3 LASTPIN (-3100 2550) SIG_NAME M_F_ECC<4>
J 0
(-3090 2560);
DISPLAY 0.659574 (-3090 2560);
PAINT MONO (-3090 2560);
DISPLAY INVISIBLE (-3090 2560);
FORCEPROP 1 LASTPIN (-3100 2550) BN 4
J 0
(-3150 2560);
DISPLAY 0.617021 (-3150 2560);
PAINT PINK (-3150 2560);
FORCEPROP 1 LAST PATH I141
J 0
(-3150 2550);
DISPLAY 0.936170 (-3150 2550);
PAINT GREEN (-3150 2550);
DISPLAY INVISIBLE (-3150 2550);
FORCEPROP 1 LAST HDL_TAP TRUE
J 0
(-2825 2425);
DISPLAY 1.234043 (-2825 2425);
PAINT GREEN (-2825 2425);
DISPLAY INVISIBLE (-2825 2425);
FORCEPROP 1 LAST BODY_TYPE PLUMBING
J 0
(-3150 2500);
DISPLAY 1.234043 (-3150 2500);
PAINT GREEN (-3150 2500);
DISPLAY INVISIBLE (-3150 2500);
FORCEPROP 2 LAST CDS_LIB mstr_standard
J 0
(-3150 2550);
DISPLAY 0.787234 (-3150 2550);
PAINT MONO (-3150 2550);
DISPLAY INVISIBLE (-3150 2550);
FORCEADD TAP..6
(-3150 2500);
FORCEPROP 3 LASTPIN (-3100 2500) SIG_NAME M_F_ECC<3>
J 0
(-3090 2510);
DISPLAY 0.659574 (-3090 2510);
PAINT MONO (-3090 2510);
DISPLAY INVISIBLE (-3090 2510);
FORCEPROP 1 LASTPIN (-3100 2500) BN 3
J 0
(-3150 2510);
DISPLAY 0.617021 (-3150 2510);
PAINT PINK (-3150 2510);
FORCEPROP 1 LAST PATH I142
J 0
(-3150 2500);
DISPLAY 0.936170 (-3150 2500);
PAINT GREEN (-3150 2500);
DISPLAY INVISIBLE (-3150 2500);
FORCEPROP 1 LAST HDL_TAP TRUE
J 0
(-2825 2375);
DISPLAY 1.234043 (-2825 2375);
PAINT GREEN (-2825 2375);
DISPLAY INVISIBLE (-2825 2375);
FORCEPROP 1 LAST BODY_TYPE PLUMBING
J 0
(-3150 2450);
DISPLAY 1.234043 (-3150 2450);
PAINT GREEN (-3150 2450);
DISPLAY INVISIBLE (-3150 2450);
FORCEPROP 2 LAST CDS_LIB mstr_standard
J 0
(-3150 2500);
DISPLAY 0.787234 (-3150 2500);
PAINT MONO (-3150 2500);
DISPLAY INVISIBLE (-3150 2500);
FORCEADD TAP..6
(-3150 2450);
FORCEPROP 3 LASTPIN (-3100 2450) SIG_NAME M_F_ECC<2>
J 0
(-3090 2460);
DISPLAY 0.659574 (-3090 2460);
PAINT MONO (-3090 2460);
DISPLAY INVISIBLE (-3090 2460);
FORCEPROP 1 LASTPIN (-3100 2450) BN 2
J 0
(-3150 2460);
DISPLAY 0.617021 (-3150 2460);
PAINT PINK (-3150 2460);
FORCEPROP 1 LAST PATH I143
J 0
(-3150 2450);
DISPLAY 0.936170 (-3150 2450);
PAINT GREEN (-3150 2450);
DISPLAY INVISIBLE (-3150 2450);
FORCEPROP 1 LAST HDL_TAP TRUE
J 0
(-2825 2325);
DISPLAY 1.234043 (-2825 2325);
PAINT GREEN (-2825 2325);
DISPLAY INVISIBLE (-2825 2325);
FORCEPROP 1 LAST BODY_TYPE PLUMBING
J 0
(-3150 2400);
DISPLAY 1.234043 (-3150 2400);
PAINT GREEN (-3150 2400);
DISPLAY INVISIBLE (-3150 2400);
FORCEPROP 2 LAST CDS_LIB mstr_standard
J 0
(-3150 2450);
DISPLAY 0.787234 (-3150 2450);
PAINT MONO (-3150 2450);
DISPLAY INVISIBLE (-3150 2450);
FORCEADD TAP..6
(-3150 2400);
FORCEPROP 3 LASTPIN (-3100 2400) SIG_NAME M_F_ECC<1>
J 0
(-3090 2410);
DISPLAY 0.659574 (-3090 2410);
PAINT MONO (-3090 2410);
DISPLAY INVISIBLE (-3090 2410);
FORCEPROP 1 LASTPIN (-3100 2400) BN 1
J 0
(-3150 2410);
DISPLAY 0.617021 (-3150 2410);
PAINT PINK (-3150 2410);
FORCEPROP 1 LAST PATH I144
J 0
(-3150 2400);
DISPLAY 0.936170 (-3150 2400);
PAINT GREEN (-3150 2400);
DISPLAY INVISIBLE (-3150 2400);
FORCEPROP 1 LAST HDL_TAP TRUE
J 0
(-2825 2275);
DISPLAY 1.234043 (-2825 2275);
PAINT GREEN (-2825 2275);
DISPLAY INVISIBLE (-2825 2275);
FORCEPROP 1 LAST BODY_TYPE PLUMBING
J 0
(-3150 2350);
DISPLAY 1.234043 (-3150 2350);
PAINT GREEN (-3150 2350);
DISPLAY INVISIBLE (-3150 2350);
FORCEPROP 2 LAST CDS_LIB mstr_standard
J 0
(-3150 2400);
DISPLAY 0.787234 (-3150 2400);
PAINT MONO (-3150 2400);
DISPLAY INVISIBLE (-3150 2400);
FORCEADD TAP..6
(-3150 2350);
FORCEPROP 3 LASTPIN (-3100 2350) SIG_NAME M_F_ECC<0>
J 0
(-3090 2360);
DISPLAY 0.659574 (-3090 2360);
PAINT MONO (-3090 2360);
DISPLAY INVISIBLE (-3090 2360);
FORCEPROP 1 LASTPIN (-3100 2350) BN 0
J 0
(-3150 2360);
DISPLAY 0.617021 (-3150 2360);
PAINT PINK (-3150 2360);
FORCEPROP 1 LAST PATH I145
J 0
(-3150 2350);
DISPLAY 0.936170 (-3150 2350);
PAINT GREEN (-3150 2350);
DISPLAY INVISIBLE (-3150 2350);
FORCEPROP 1 LAST HDL_TAP TRUE
J 0
(-2825 2225);
DISPLAY 1.234043 (-2825 2225);
PAINT GREEN (-2825 2225);
DISPLAY INVISIBLE (-2825 2225);
FORCEPROP 1 LAST BODY_TYPE PLUMBING
J 0
(-3150 2300);
DISPLAY 1.234043 (-3150 2300);
PAINT GREEN (-3150 2300);
DISPLAY INVISIBLE (-3150 2300);
FORCEPROP 2 LAST CDS_LIB mstr_standard
J 0
(-3150 2350);
DISPLAY 0.787234 (-3150 2350);
PAINT MONO (-3150 2350);
DISPLAY INVISIBLE (-3150 2350);
FORCEADD OFFPAGE..1
(-3800 2700);
FORCEPROP 2 LAST $XR1 53 
J 0
(-4141 2700);
DISPLAY 0.638298 (-4141 2700);
PAINT MONO (-4141 2700);
FORCEPROP 2 LAST $XR0 28 
J 0
(-4051 2700);
DISPLAY 0.638298 (-4051 2700);
PAINT MONO (-4051 2700);
FORCEPROP 2 LAST PATH I146
J 0
(-3750 2775);
DISPLAY 0.787234 (-3750 2775);
PAINT MONO (-3750 2775);
DISPLAY INVISIBLE (-3750 2775);
FORCEPROP 1 LAST COMMENT_BODY TRUE
J 0
(-3675 2600);
DISPLAY 0.936170 (-3675 2600);
PAINT GREEN (-3675 2600);
DISPLAY INVISIBLE (-3675 2600);
FORCEPROP 1 LAST OFFPAGE TRUE
J 0
(-3475 2575);
DISPLAY 0.936170 (-3475 2575);
PAINT GREEN (-3475 2575);
DISPLAY INVISIBLE (-3475 2575);
FORCEPROP 2 LAST CDS_LIB mstr_standard
J 0
(-3800 2700);
DISPLAY 0.787234 (-3800 2700);
PAINT MONO (-3800 2700);
DISPLAY INVISIBLE (-3800 2700);
FORCEADD OFFPAGE..1
(-3950 2050);
FORCEPROP 2 LAST $XR1 53 
J 0
(-4291 2050);
DISPLAY 0.638298 (-4291 2050);
PAINT MONO (-4291 2050);
FORCEPROP 2 LAST $XR0 28 
J 0
(-4201 2050);
DISPLAY 0.638298 (-4201 2050);
PAINT MONO (-4201 2050);
FORCEPROP 2 LAST PATH I147
J 0
(-3900 2125);
DISPLAY 0.787234 (-3900 2125);
PAINT MONO (-3900 2125);
DISPLAY INVISIBLE (-3900 2125);
FORCEPROP 1 LAST COMMENT_BODY TRUE
J 0
(-3825 1950);
DISPLAY 0.936170 (-3825 1950);
PAINT GREEN (-3825 1950);
DISPLAY INVISIBLE (-3825 1950);
FORCEPROP 1 LAST OFFPAGE TRUE
J 0
(-3625 1925);
DISPLAY 0.936170 (-3625 1925);
PAINT GREEN (-3625 1925);
DISPLAY INVISIBLE (-3625 1925);
FORCEPROP 2 LAST CDS_LIB mstr_standard
J 0
(-3950 2050);
DISPLAY 0.787234 (-3950 2050);
PAINT MONO (-3950 2050);
DISPLAY INVISIBLE (-3950 2050);
FORCEADD OFFPAGE..5
(-3975 2100);
FORCEPROP 2 LAST $XR1 28 
J 0
(-4319 2100);
DISPLAY 0.638298 (-4319 2100);
PAINT MONO (-4319 2100);
FORCEPROP 2 LAST $XR0 53 
J 0
(-4229 2100);
DISPLAY 0.638298 (-4229 2100);
PAINT MONO (-4229 2100);
FORCEPROP 2 LAST PATH I148
J 0
(-3925 2175);
DISPLAY 0.787234 (-3925 2175);
PAINT MONO (-3925 2175);
DISPLAY INVISIBLE (-3925 2175);
FORCEPROP 1 LAST COMMENT_BODY TRUE
J 0
(-3875 2025);
DISPLAY 1.404255 (-3875 2025);
PAINT GREEN (-3875 2025);
DISPLAY INVISIBLE (-3875 2025);
FORCEPROP 1 LAST OFFPAGE TRUE
J 0
(-3650 1975);
DISPLAY 1.404255 (-3650 1975);
PAINT GREEN (-3650 1975);
DISPLAY INVISIBLE (-3650 1975);
FORCEPROP 2 LAST CDS_LIB mstr_standard
J 0
(-3975 2100);
DISPLAY 0.787234 (-3975 2100);
PAINT MONO (-3975 2100);
DISPLAY INVISIBLE (-3975 2100);
FORCEADD OFFPAGE..1
(-3800 2650);
FORCEPROP 2 LAST $XR5 53 
J 0
(-4501 2650);
DISPLAY 0.638298 (-4501 2650);
PAINT MONO (-4501 2650);
FORCEPROP 2 LAST $XR4 52 
J 0
(-4411 2650);
DISPLAY 0.638298 (-4411 2650);
PAINT MONO (-4411 2650);
FORCEPROP 2 LAST $XR3 51 
J 0
(-4321 2650);
DISPLAY 0.638298 (-4321 2650);
PAINT MONO (-4321 2650);
FORCEPROP 2 LAST $XR2 50 
J 0
(-4231 2650);
DISPLAY 0.638298 (-4231 2650);
PAINT MONO (-4231 2650);
FORCEPROP 2 LAST $XR1 49 
J 0
(-4141 2650);
DISPLAY 0.638298 (-4141 2650);
PAINT MONO (-4141 2650);
FORCEPROP 2 LAST $XR0 21 
J 0
(-4051 2650);
DISPLAY 0.638298 (-4051 2650);
PAINT MONO (-4051 2650);
FORCEPROP 2 LAST PATH I149
J 0
(-3750 2725);
DISPLAY 0.787234 (-3750 2725);
PAINT MONO (-3750 2725);
DISPLAY INVISIBLE (-3750 2725);
FORCEPROP 1 LAST COMMENT_BODY TRUE
J 0
(-3675 2550);
DISPLAY 0.936170 (-3675 2550);
PAINT GREEN (-3675 2550);
DISPLAY INVISIBLE (-3675 2550);
FORCEPROP 1 LAST OFFPAGE TRUE
J 0
(-3475 2525);
DISPLAY 0.936170 (-3475 2525);
PAINT GREEN (-3475 2525);
DISPLAY INVISIBLE (-3475 2525);
FORCEPROP 2 LAST CDS_LIB mstr_standard
J 0
(-3800 2650);
DISPLAY 0.787234 (-3800 2650);
PAINT MONO (-3800 2650);
DISPLAY INVISIBLE (-3800 2650);
FORCEADD TAP..6
R 2
(700 4750);
FORCEPROP 3 LASTPIN (650 4750) SIG_NAME M_F_DQS_DP<13>
J 0
(660 4760);
DISPLAY 0.659574 (660 4760);
PAINT MONO (660 4760);
DISPLAY INVISIBLE (660 4760);
FORCEPROP 1 LASTPIN (650 4750) BN 13
J 2
(700 4760);
DISPLAY 0.617021 (700 4760);
PAINT PINK (700 4760);
FORCEPROP 1 LAST PATH I15
J 2
(700 4750);
DISPLAY 0.936170 (700 4750);
PAINT GREEN (700 4750);
DISPLAY INVISIBLE (700 4750);
FORCEPROP 1 LAST HDL_TAP TRUE
J 2
(375 4625);
DISPLAY 1.234043 (375 4625);
PAINT GREEN (375 4625);
DISPLAY INVISIBLE (375 4625);
FORCEPROP 1 LAST BODY_TYPE PLUMBING
J 2
(700 4700);
DISPLAY 1.234043 (700 4700);
PAINT GREEN (700 4700);
DISPLAY INVISIBLE (700 4700);
FORCEPROP 2 LAST CDS_LIB mstr_standard
J 0
(700 4750);
DISPLAY 0.787234 (700 4750);
PAINT MONO (700 4750);
DISPLAY INVISIBLE (700 4750);
FORCEADD OFFPAGE..6
(-3800 2750);
FORCEPROP 2 LAST $XR1 53 
J 0
(-4139 2750);
DISPLAY 0.638298 (-4139 2750);
PAINT MONO (-4139 2750);
FORCEPROP 2 LAST $XR0 28 
J 0
(-4049 2750);
DISPLAY 0.638298 (-4049 2750);
PAINT MONO (-4049 2750);
FORCEPROP 2 LAST PATH I150
J 0
(-3750 2825);
DISPLAY 0.787234 (-3750 2825);
PAINT MONO (-3750 2825);
DISPLAY INVISIBLE (-3750 2825);
FORCEPROP 1 LAST COMMENT_BODY TRUE
J 0
(-3700 2675);
DISPLAY 0.936170 (-3700 2675);
PAINT GREEN (-3700 2675);
DISPLAY INVISIBLE (-3700 2675);
FORCEPROP 1 LAST OFFPAGE TRUE
J 0
(-3475 2625);
DISPLAY 0.936170 (-3475 2625);
PAINT GREEN (-3475 2625);
DISPLAY INVISIBLE (-3475 2625);
FORCEPROP 2 LAST CDS_LIB mstr_standard
J 0
(-3800 2750);
DISPLAY 0.787234 (-3800 2750);
PAINT MONO (-3800 2750);
DISPLAY INVISIBLE (-3800 2750);
FORCEADD TAP..6
(-3150 3550);
FORCEPROP 3 LASTPIN (-3100 3550) SIG_NAME M_F_CLK_DP<3>
J 0
(-3090 3560);
DISPLAY 0.659574 (-3090 3560);
PAINT MONO (-3090 3560);
DISPLAY INVISIBLE (-3090 3560);
FORCEPROP 1 LASTPIN (-3100 3550) BN 3
J 0
(-3150 3560);
DISPLAY 0.617021 (-3150 3560);
PAINT PINK (-3150 3560);
FORCEPROP 1 LAST PATH I152
J 0
(-3150 3550);
DISPLAY 0.936170 (-3150 3550);
PAINT GREEN (-3150 3550);
DISPLAY INVISIBLE (-3150 3550);
FORCEPROP 1 LAST HDL_TAP TRUE
J 0
(-2825 3425);
DISPLAY 1.234043 (-2825 3425);
PAINT GREEN (-2825 3425);
DISPLAY INVISIBLE (-2825 3425);
FORCEPROP 1 LAST BODY_TYPE PLUMBING
J 0
(-3150 3500);
DISPLAY 1.234043 (-3150 3500);
PAINT GREEN (-3150 3500);
DISPLAY INVISIBLE (-3150 3500);
FORCEPROP 2 LAST CDS_LIB mstr_standard
J 0
(-3150 3550);
DISPLAY 0.787234 (-3150 3550);
PAINT MONO (-3150 3550);
DISPLAY INVISIBLE (-3150 3550);
FORCEADD TAP..6
(-3150 3450);
FORCEPROP 3 LASTPIN (-3100 3450) SIG_NAME M_F_CLK_DP<2>
J 0
(-3090 3460);
DISPLAY 0.659574 (-3090 3460);
PAINT MONO (-3090 3460);
DISPLAY INVISIBLE (-3090 3460);
FORCEPROP 1 LASTPIN (-3100 3450) BN 2
J 0
(-3150 3460);
DISPLAY 0.617021 (-3150 3460);
PAINT PINK (-3150 3460);
FORCEPROP 1 LAST PATH I153
J 0
(-3150 3450);
DISPLAY 0.936170 (-3150 3450);
PAINT GREEN (-3150 3450);
DISPLAY INVISIBLE (-3150 3450);
FORCEPROP 1 LAST HDL_TAP TRUE
J 0
(-2825 3325);
DISPLAY 1.234043 (-2825 3325);
PAINT GREEN (-2825 3325);
DISPLAY INVISIBLE (-2825 3325);
FORCEPROP 1 LAST BODY_TYPE PLUMBING
J 0
(-3150 3400);
DISPLAY 1.234043 (-3150 3400);
PAINT GREEN (-3150 3400);
DISPLAY INVISIBLE (-3150 3400);
FORCEPROP 2 LAST CDS_LIB mstr_standard
J 0
(-3150 3450);
DISPLAY 0.787234 (-3150 3450);
PAINT MONO (-3150 3450);
DISPLAY INVISIBLE (-3150 3450);
FORCEADD TAP..6
(-3350 3500);
FORCEPROP 3 LASTPIN (-3300 3500) SIG_NAME M_F_CLK_DN<3>
J 0
(-3290 3510);
DISPLAY 0.659574 (-3290 3510);
PAINT MONO (-3290 3510);
DISPLAY INVISIBLE (-3290 3510);
FORCEPROP 1 LASTPIN (-3300 3500) BN 3
J 0
(-3350 3510);
DISPLAY 0.617021 (-3350 3510);
PAINT PINK (-3350 3510);
FORCEPROP 1 LAST PATH I154
J 0
(-3350 3500);
DISPLAY 0.936170 (-3350 3500);
PAINT GREEN (-3350 3500);
DISPLAY INVISIBLE (-3350 3500);
FORCEPROP 1 LAST HDL_TAP TRUE
J 0
(-3025 3375);
DISPLAY 1.234043 (-3025 3375);
PAINT GREEN (-3025 3375);
DISPLAY INVISIBLE (-3025 3375);
FORCEPROP 1 LAST BODY_TYPE PLUMBING
J 0
(-3350 3450);
DISPLAY 1.234043 (-3350 3450);
PAINT GREEN (-3350 3450);
DISPLAY INVISIBLE (-3350 3450);
FORCEPROP 2 LAST CDS_LIB mstr_standard
J 0
(-3350 3500);
DISPLAY 0.787234 (-3350 3500);
PAINT MONO (-3350 3500);
DISPLAY INVISIBLE (-3350 3500);
FORCEADD TAP..6
(-3350 3400);
FORCEPROP 3 LASTPIN (-3300 3400) SIG_NAME M_F_CLK_DN<2>
J 0
(-3290 3410);
DISPLAY 0.659574 (-3290 3410);
PAINT MONO (-3290 3410);
DISPLAY INVISIBLE (-3290 3410);
FORCEPROP 1 LASTPIN (-3300 3400) BN 2
J 0
(-3350 3410);
DISPLAY 0.617021 (-3350 3410);
PAINT PINK (-3350 3410);
FORCEPROP 1 LAST PATH I155
J 0
(-3350 3400);
DISPLAY 0.936170 (-3350 3400);
PAINT GREEN (-3350 3400);
DISPLAY INVISIBLE (-3350 3400);
FORCEPROP 1 LAST HDL_TAP TRUE
J 0
(-3025 3275);
DISPLAY 1.234043 (-3025 3275);
PAINT GREEN (-3025 3275);
DISPLAY INVISIBLE (-3025 3275);
FORCEPROP 1 LAST BODY_TYPE PLUMBING
J 0
(-3350 3350);
DISPLAY 1.234043 (-3350 3350);
PAINT GREEN (-3350 3350);
DISPLAY INVISIBLE (-3350 3350);
FORCEPROP 2 LAST CDS_LIB mstr_standard
J 0
(-3350 3400);
DISPLAY 0.787234 (-3350 3400);
PAINT MONO (-3350 3400);
DISPLAY INVISIBLE (-3350 3400);
FORCEADD OFFPAGE..1
(-3850 3550);
FORCEPROP 2 LAST $XR1 53 
J 0
(-4191 3550);
DISPLAY 0.638298 (-4191 3550);
PAINT MONO (-4191 3550);
FORCEPROP 2 LAST $XR0 28 
J 0
(-4101 3550);
DISPLAY 0.638298 (-4101 3550);
PAINT MONO (-4101 3550);
FORCEPROP 2 LAST PATH I156
J 0
(-3800 3625);
DISPLAY 0.787234 (-3800 3625);
PAINT MONO (-3800 3625);
DISPLAY INVISIBLE (-3800 3625);
FORCEPROP 1 LAST COMMENT_BODY TRUE
J 0
(-3725 3450);
DISPLAY 0.936170 (-3725 3450);
PAINT GREEN (-3725 3450);
DISPLAY INVISIBLE (-3725 3450);
FORCEPROP 1 LAST OFFPAGE TRUE
J 0
(-3525 3425);
DISPLAY 0.936170 (-3525 3425);
PAINT GREEN (-3525 3425);
DISPLAY INVISIBLE (-3525 3425);
FORCEPROP 2 LAST CDS_LIB mstr_standard
J 0
(-3850 3550);
DISPLAY 0.787234 (-3850 3550);
PAINT MONO (-3850 3550);
DISPLAY INVISIBLE (-3850 3550);
FORCEADD OFFPAGE..1
(-3850 3600);
FORCEPROP 2 LAST $XR1 53 
J 0
(-4191 3600);
DISPLAY 0.638298 (-4191 3600);
PAINT MONO (-4191 3600);
FORCEPROP 2 LAST $XR0 28 
J 0
(-4101 3600);
DISPLAY 0.638298 (-4101 3600);
PAINT MONO (-4101 3600);
FORCEPROP 2 LAST PATH I157
J 0
(-3800 3675);
DISPLAY 0.787234 (-3800 3675);
PAINT MONO (-3800 3675);
DISPLAY INVISIBLE (-3800 3675);
FORCEPROP 1 LAST COMMENT_BODY TRUE
J 0
(-3725 3500);
DISPLAY 0.936170 (-3725 3500);
PAINT GREEN (-3725 3500);
DISPLAY INVISIBLE (-3725 3500);
FORCEPROP 1 LAST OFFPAGE TRUE
J 0
(-3525 3475);
DISPLAY 0.936170 (-3525 3475);
PAINT GREEN (-3525 3475);
DISPLAY INVISIBLE (-3525 3475);
FORCEPROP 2 LAST CDS_LIB mstr_standard
J 0
(-3850 3600);
DISPLAY 0.787234 (-3850 3600);
PAINT MONO (-3850 3600);
DISPLAY INVISIBLE (-3850 3600);
FORCEADD TAP..6
(-3150 3250);
FORCEPROP 3 LASTPIN (-3100 3250) SIG_NAME M_F_CS_N<7>
J 0
(-3090 3260);
DISPLAY 0.659574 (-3090 3260);
PAINT MONO (-3090 3260);
DISPLAY INVISIBLE (-3090 3260);
FORCEPROP 1 LASTPIN (-3100 3250) BN 7
J 0
(-3150 3260);
DISPLAY 0.617021 (-3150 3260);
PAINT PINK (-3150 3260);
FORCEPROP 1 LAST PATH I158
J 0
(-3150 3250);
DISPLAY 0.936170 (-3150 3250);
PAINT GREEN (-3150 3250);
DISPLAY INVISIBLE (-3150 3250);
FORCEPROP 1 LAST HDL_TAP TRUE
J 0
(-2825 3125);
DISPLAY 1.234043 (-2825 3125);
PAINT GREEN (-2825 3125);
DISPLAY INVISIBLE (-2825 3125);
FORCEPROP 1 LAST BODY_TYPE PLUMBING
J 0
(-3150 3200);
DISPLAY 1.234043 (-3150 3200);
PAINT GREEN (-3150 3200);
DISPLAY INVISIBLE (-3150 3200);
FORCEPROP 2 LAST CDS_LIB mstr_standard
J 0
(-3150 3250);
DISPLAY 0.787234 (-3150 3250);
PAINT MONO (-3150 3250);
DISPLAY INVISIBLE (-3150 3250);
FORCEADD TAP..6
(-3150 3200);
FORCEPROP 3 LASTPIN (-3100 3200) SIG_NAME M_F_CS_N<6>
J 0
(-3090 3210);
DISPLAY 0.659574 (-3090 3210);
PAINT MONO (-3090 3210);
DISPLAY INVISIBLE (-3090 3210);
FORCEPROP 1 LASTPIN (-3100 3200) BN 6
J 0
(-3150 3210);
DISPLAY 0.617021 (-3150 3210);
PAINT PINK (-3150 3210);
FORCEPROP 1 LAST PATH I159
J 0
(-3150 3200);
DISPLAY 0.936170 (-3150 3200);
PAINT GREEN (-3150 3200);
DISPLAY INVISIBLE (-3150 3200);
FORCEPROP 1 LAST HDL_TAP TRUE
J 0
(-2825 3075);
DISPLAY 1.234043 (-2825 3075);
PAINT GREEN (-2825 3075);
DISPLAY INVISIBLE (-2825 3075);
FORCEPROP 1 LAST BODY_TYPE PLUMBING
J 0
(-3150 3150);
DISPLAY 1.234043 (-3150 3150);
PAINT GREEN (-3150 3150);
DISPLAY INVISIBLE (-3150 3150);
FORCEPROP 2 LAST CDS_LIB mstr_standard
J 0
(-3150 3200);
DISPLAY 0.787234 (-3150 3200);
PAINT MONO (-3150 3200);
DISPLAY INVISIBLE (-3150 3200);
FORCEADD PVDDQ_DEF..1
(-1150 2475);
FORCEPROP 3 LASTPIN (-1150 2425) SIG_NAME PVDDQ_DEF\g
J 0
(-1140 2435);
DISPLAY 0.659574 (-1140 2435);
PAINT MONO (-1140 2435);
DISPLAY INVISIBLE (-1140 2435);
FORCEPROP 1 LAST HDL_POWER PVDDQ_DEF
J 1
(-1150 2525);
DISPLAY 0.872340 (-1150 2525);
PAINT GREEN (-1150 2525);
DISPLAY INVISIBLE (-1150 2525);
FORCEPROP 2 LAST ROOM DDR4_CH_C
J 0
(-1150 2575);
DISPLAY 0.787234 (-1150 2575);
PAINT ORANGE (-1150 2575);
DISPLAY INVISIBLE (-1150 2575);
FORCEPROP 1 LAST PATH I16
J 0
(-1100 2500);
DISPLAY 0.872340 (-1100 2500);
PAINT AQUA (-1100 2500);
DISPLAY INVISIBLE (-1100 2500);
FORCEPROP 1 LAST BODY_TYPE PLUMBING
J 0
(-1195 2432);
DISPLAY 0.340426 (-1195 2432);
PAINT GREEN (-1195 2432);
DISPLAY INVISIBLE (-1195 2432);
FORCEPROP 2 LAST CDS_LIB mstr_symbols
J 0
(-1150 2475);
PAINT ORANGE (-1150 2475);
DISPLAY INVISIBLE (-1150 2475);
FORCEPROP 2 LAST BOM_COST MEM
J 0
(-1150 2480);
PAINT ORANGE (-1150 2480);
DISPLAY INVISIBLE (-1150 2480);
FORCEPROP 1 LAST VOLTAGE 1.2V
J 0
(-1195 2432);
DISPLAY 0.340426 (-1195 2432);
PAINT SKYBLUE (-1195 2432);
DISPLAY INVISIBLE (-1195 2432);
FORCEADD TAP..6
(-3150 3150);
FORCEPROP 3 LASTPIN (-3100 3150) SIG_NAME M_F_CS_N<5>
J 0
(-3090 3160);
DISPLAY 0.659574 (-3090 3160);
PAINT MONO (-3090 3160);
DISPLAY INVISIBLE (-3090 3160);
FORCEPROP 1 LASTPIN (-3100 3150) BN 5
J 0
(-3150 3160);
DISPLAY 0.617021 (-3150 3160);
PAINT PINK (-3150 3160);
FORCEPROP 1 LAST PATH I160
J 0
(-3150 3150);
DISPLAY 0.936170 (-3150 3150);
PAINT GREEN (-3150 3150);
DISPLAY INVISIBLE (-3150 3150);
FORCEPROP 1 LAST HDL_TAP TRUE
J 0
(-2825 3025);
DISPLAY 1.234043 (-2825 3025);
PAINT GREEN (-2825 3025);
DISPLAY INVISIBLE (-2825 3025);
FORCEPROP 1 LAST BODY_TYPE PLUMBING
J 0
(-3150 3100);
DISPLAY 1.234043 (-3150 3100);
PAINT GREEN (-3150 3100);
DISPLAY INVISIBLE (-3150 3100);
FORCEPROP 2 LAST CDS_LIB mstr_standard
J 0
(-3150 3150);
DISPLAY 0.787234 (-3150 3150);
PAINT MONO (-3150 3150);
DISPLAY INVISIBLE (-3150 3150);
FORCEADD TAP..6
(-3150 3100);
FORCEPROP 3 LASTPIN (-3100 3100) SIG_NAME M_F_CS_N<4>
J 0
(-3090 3110);
DISPLAY 0.659574 (-3090 3110);
PAINT MONO (-3090 3110);
DISPLAY INVISIBLE (-3090 3110);
FORCEPROP 1 LASTPIN (-3100 3100) BN 4
J 0
(-3150 3110);
DISPLAY 0.617021 (-3150 3110);
PAINT PINK (-3150 3110);
FORCEPROP 1 LAST PATH I161
J 0
(-3150 3100);
DISPLAY 0.936170 (-3150 3100);
PAINT GREEN (-3150 3100);
DISPLAY INVISIBLE (-3150 3100);
FORCEPROP 1 LAST HDL_TAP TRUE
J 0
(-2825 2975);
DISPLAY 1.234043 (-2825 2975);
PAINT GREEN (-2825 2975);
DISPLAY INVISIBLE (-2825 2975);
FORCEPROP 1 LAST BODY_TYPE PLUMBING
J 0
(-3150 3050);
DISPLAY 1.234043 (-3150 3050);
PAINT GREEN (-3150 3050);
DISPLAY INVISIBLE (-3150 3050);
FORCEPROP 2 LAST CDS_LIB mstr_standard
J 0
(-3150 3100);
DISPLAY 0.787234 (-3150 3100);
PAINT MONO (-3150 3100);
DISPLAY INVISIBLE (-3150 3100);
FORCEADD OFFPAGE..1
(-3800 3300);
FORCEPROP 2 LAST $XR1 53 
J 0
(-4141 3300);
DISPLAY 0.638298 (-4141 3300);
PAINT MONO (-4141 3300);
FORCEPROP 2 LAST $XR0 28 
J 0
(-4051 3300);
DISPLAY 0.638298 (-4051 3300);
PAINT MONO (-4051 3300);
FORCEPROP 2 LAST PATH I163
J 0
(-3750 3375);
DISPLAY 0.787234 (-3750 3375);
PAINT MONO (-3750 3375);
DISPLAY INVISIBLE (-3750 3375);
FORCEPROP 1 LAST COMMENT_BODY TRUE
J 0
(-3675 3200);
DISPLAY 0.936170 (-3675 3200);
PAINT GREEN (-3675 3200);
DISPLAY INVISIBLE (-3675 3200);
FORCEPROP 1 LAST OFFPAGE TRUE
J 0
(-3475 3175);
DISPLAY 0.936170 (-3475 3175);
PAINT GREEN (-3475 3175);
DISPLAY INVISIBLE (-3475 3175);
FORCEPROP 2 LAST CDS_LIB mstr_standard
J 0
(-3800 3300);
DISPLAY 0.787234 (-3800 3300);
PAINT MONO (-3800 3300);
DISPLAY INVISIBLE (-3800 3300);
FORCEADD OFFPAGE..1
(-3800 3050);
FORCEPROP 2 LAST $XR1 53 
J 0
(-4141 3050);
DISPLAY 0.638298 (-4141 3050);
PAINT MONO (-4141 3050);
FORCEPROP 2 LAST $XR0 28 
J 0
(-4051 3050);
DISPLAY 0.638298 (-4051 3050);
PAINT MONO (-4051 3050);
FORCEPROP 2 LAST PATH I164
J 0
(-3750 3125);
DISPLAY 0.787234 (-3750 3125);
PAINT MONO (-3750 3125);
DISPLAY INVISIBLE (-3750 3125);
FORCEPROP 1 LAST COMMENT_BODY TRUE
J 0
(-3675 2950);
DISPLAY 0.936170 (-3675 2950);
PAINT GREEN (-3675 2950);
DISPLAY INVISIBLE (-3675 2950);
FORCEPROP 1 LAST OFFPAGE TRUE
J 0
(-3475 2925);
DISPLAY 0.936170 (-3475 2925);
PAINT GREEN (-3475 2925);
DISPLAY INVISIBLE (-3475 2925);
FORCEPROP 2 LAST CDS_LIB mstr_standard
J 0
(-3800 3050);
DISPLAY 0.787234 (-3800 3050);
PAINT MONO (-3800 3050);
DISPLAY INVISIBLE (-3800 3050);
FORCEADD TAP..6
(-3150 3000);
FORCEPROP 3 LASTPIN (-3100 3000) SIG_NAME M_F_CKE<3>
J 0
(-3090 3010);
DISPLAY 0.659574 (-3090 3010);
PAINT MONO (-3090 3010);
DISPLAY INVISIBLE (-3090 3010);
FORCEPROP 1 LASTPIN (-3100 3000) BN 3
J 0
(-3150 3010);
DISPLAY 0.617021 (-3150 3010);
PAINT PINK (-3150 3010);
FORCEPROP 1 LAST PATH I165
J 0
(-3150 3000);
DISPLAY 0.936170 (-3150 3000);
PAINT GREEN (-3150 3000);
DISPLAY INVISIBLE (-3150 3000);
FORCEPROP 1 LAST HDL_TAP TRUE
J 0
(-2825 2875);
DISPLAY 1.234043 (-2825 2875);
PAINT GREEN (-2825 2875);
DISPLAY INVISIBLE (-2825 2875);
FORCEPROP 1 LAST BODY_TYPE PLUMBING
J 0
(-3150 2950);
DISPLAY 1.234043 (-3150 2950);
PAINT GREEN (-3150 2950);
DISPLAY INVISIBLE (-3150 2950);
FORCEPROP 2 LAST CDS_LIB mstr_standard
J 0
(-3150 3000);
DISPLAY 0.787234 (-3150 3000);
PAINT MONO (-3150 3000);
DISPLAY INVISIBLE (-3150 3000);
FORCEADD TAP..6
(-3150 2950);
FORCEPROP 3 LASTPIN (-3100 2950) SIG_NAME M_F_CKE<2>
J 0
(-3090 2960);
DISPLAY 0.659574 (-3090 2960);
PAINT MONO (-3090 2960);
DISPLAY INVISIBLE (-3090 2960);
FORCEPROP 1 LASTPIN (-3100 2950) BN 2
J 0
(-3150 2960);
DISPLAY 0.617021 (-3150 2960);
PAINT PINK (-3150 2960);
FORCEPROP 1 LAST PATH I166
J 0
(-3150 2950);
DISPLAY 0.936170 (-3150 2950);
PAINT GREEN (-3150 2950);
DISPLAY INVISIBLE (-3150 2950);
FORCEPROP 1 LAST HDL_TAP TRUE
J 0
(-2825 2825);
DISPLAY 1.234043 (-2825 2825);
PAINT GREEN (-2825 2825);
DISPLAY INVISIBLE (-2825 2825);
FORCEPROP 1 LAST BODY_TYPE PLUMBING
J 0
(-3150 2900);
DISPLAY 1.234043 (-3150 2900);
PAINT GREEN (-3150 2900);
DISPLAY INVISIBLE (-3150 2900);
FORCEPROP 2 LAST CDS_LIB mstr_standard
J 0
(-3150 2950);
DISPLAY 0.787234 (-3150 2950);
PAINT MONO (-3150 2950);
DISPLAY INVISIBLE (-3150 2950);
FORCEADD TAP..6
(-3150 2850);
FORCEPROP 3 LASTPIN (-3100 2850) SIG_NAME M_F_ODT<3>
J 0
(-3090 2860);
DISPLAY 0.659574 (-3090 2860);
PAINT MONO (-3090 2860);
DISPLAY INVISIBLE (-3090 2860);
FORCEPROP 1 LASTPIN (-3100 2850) BN 3
J 0
(-3150 2860);
DISPLAY 0.617021 (-3150 2860);
PAINT PINK (-3150 2860);
FORCEPROP 1 LAST PATH I167
J 0
(-3150 2850);
DISPLAY 0.936170 (-3150 2850);
PAINT GREEN (-3150 2850);
DISPLAY INVISIBLE (-3150 2850);
FORCEPROP 1 LAST HDL_TAP TRUE
J 0
(-2825 2725);
DISPLAY 1.234043 (-2825 2725);
PAINT GREEN (-2825 2725);
DISPLAY INVISIBLE (-2825 2725);
FORCEPROP 1 LAST BODY_TYPE PLUMBING
J 0
(-3150 2800);
DISPLAY 1.234043 (-3150 2800);
PAINT GREEN (-3150 2800);
DISPLAY INVISIBLE (-3150 2800);
FORCEPROP 2 LAST CDS_LIB mstr_standard
J 0
(-3150 2850);
DISPLAY 0.787234 (-3150 2850);
PAINT MONO (-3150 2850);
DISPLAY INVISIBLE (-3150 2850);
FORCEADD TAP..6
(-3150 2800);
FORCEPROP 3 LASTPIN (-3100 2800) SIG_NAME M_F_ODT<2>
J 0
(-3090 2810);
DISPLAY 0.659574 (-3090 2810);
PAINT MONO (-3090 2810);
DISPLAY INVISIBLE (-3090 2810);
FORCEPROP 1 LASTPIN (-3100 2800) BN 2
J 0
(-3150 2810);
DISPLAY 0.617021 (-3150 2810);
PAINT PINK (-3150 2810);
FORCEPROP 1 LAST PATH I168
J 0
(-3150 2800);
DISPLAY 0.936170 (-3150 2800);
PAINT GREEN (-3150 2800);
DISPLAY INVISIBLE (-3150 2800);
FORCEPROP 1 LAST HDL_TAP TRUE
J 0
(-2825 2675);
DISPLAY 1.234043 (-2825 2675);
PAINT GREEN (-2825 2675);
DISPLAY INVISIBLE (-2825 2675);
FORCEPROP 1 LAST BODY_TYPE PLUMBING
J 0
(-3150 2750);
DISPLAY 1.234043 (-3150 2750);
PAINT GREEN (-3150 2750);
DISPLAY INVISIBLE (-3150 2750);
FORCEPROP 2 LAST CDS_LIB mstr_standard
J 0
(-3150 2800);
DISPLAY 0.787234 (-3150 2800);
PAINT MONO (-3150 2800);
DISPLAY INVISIBLE (-3150 2800);
FORCEADD OFFPAGE..1
(-3800 2900);
FORCEPROP 2 LAST $XR1 53 
J 0
(-4141 2900);
DISPLAY 0.638298 (-4141 2900);
PAINT MONO (-4141 2900);
FORCEPROP 2 LAST $XR0 28 
J 0
(-4051 2900);
DISPLAY 0.638298 (-4051 2900);
PAINT MONO (-4051 2900);
FORCEPROP 2 LAST PATH I169
J 0
(-3750 2975);
DISPLAY 0.787234 (-3750 2975);
PAINT MONO (-3750 2975);
DISPLAY INVISIBLE (-3750 2975);
FORCEPROP 1 LAST COMMENT_BODY TRUE
J 0
(-3675 2800);
DISPLAY 0.936170 (-3675 2800);
PAINT GREEN (-3675 2800);
DISPLAY INVISIBLE (-3675 2800);
FORCEPROP 1 LAST OFFPAGE TRUE
J 0
(-3475 2775);
DISPLAY 0.936170 (-3475 2775);
PAINT GREEN (-3475 2775);
DISPLAY INVISIBLE (-3475 2775);
FORCEPROP 2 LAST CDS_LIB mstr_standard
J 0
(-3800 2900);
DISPLAY 0.787234 (-3800 2900);
PAINT MONO (-3800 2900);
DISPLAY INVISIBLE (-3800 2900);
FORCEADD PVTT_DEF..1
(-900 2600);
FORCEPROP 3 LASTPIN (-900 2550) SIG_NAME PVTT_DEF\g
J 0
(-890 2560);
DISPLAY 0.659574 (-890 2560);
PAINT MONO (-890 2560);
DISPLAY INVISIBLE (-890 2560);
FORCEPROP 1 LAST HDL_POWER PVTT_DEF
J 1
(-900 2650);
DISPLAY 0.872340 (-900 2650);
PAINT GREEN (-900 2650);
DISPLAY INVISIBLE (-900 2650);
FORCEPROP 2 LAST ROOM DDR4_CH_C
J 0
(-900 2700);
DISPLAY 0.787234 (-900 2700);
PAINT ORANGE (-900 2700);
DISPLAY INVISIBLE (-900 2700);
FORCEPROP 1 LAST PATH I17
J 0
(-850 2625);
DISPLAY 0.872340 (-850 2625);
PAINT AQUA (-850 2625);
DISPLAY INVISIBLE (-850 2625);
FORCEPROP 1 LAST BODY_TYPE PLUMBING
J 0
(-945 2557);
DISPLAY 0.340426 (-945 2557);
PAINT GREEN (-945 2557);
DISPLAY INVISIBLE (-945 2557);
FORCEPROP 2 LAST CDS_LIB mstr_symbols
J 0
(-900 2600);
PAINT ORANGE (-900 2600);
DISPLAY INVISIBLE (-900 2600);
FORCEPROP 2 LAST BOM_COST MEM
J 0
(-900 2605);
PAINT ORANGE (-900 2605);
DISPLAY INVISIBLE (-900 2605);
FORCEPROP 1 LAST VOLTAGE 0.6V
J 0
(-945 2557);
DISPLAY 0.340426 (-945 2557);
PAINT SKYBLUE (-945 2557);
DISPLAY INVISIBLE (-945 2557);
FORCEADD SCONN288_H44441003..4
(-50 1900);
FORCEPROP 2 LASTPIN (450 2700) $PN 145
J 0
(460 2710);
DISPLAY 0.617021 (460 2710);
PAINT ORANGE (460 2710);
FORCEPROP 2 LASTPIN (450 2750) $PN 1
J 0
(460 2760);
DISPLAY 0.617021 (460 2760);
PAINT ORANGE (460 2760);
FORCEPROP 2 LASTPIN (-550 1050) $PN 236
J 2
(-560 1060);
DISPLAY 0.617021 (-560 1060);
PAINT ORANGE (-560 1060);
FORCEPROP 2 LASTPIN (-550 1100) $PN 233
J 2
(-560 1110);
DISPLAY 0.617021 (-560 1110);
PAINT ORANGE (-560 1110);
FORCEPROP 2 LASTPIN (-550 1150) $PN 231
J 2
(-560 1160);
DISPLAY 0.617021 (-560 1160);
PAINT ORANGE (-560 1160);
FORCEPROP 2 LASTPIN (-550 1200) $PN 229
J 2
(-560 1210);
DISPLAY 0.617021 (-560 1210);
PAINT ORANGE (-560 1210);
FORCEPROP 2 LASTPIN (-550 1250) $PN 226
J 2
(-560 1260);
DISPLAY 0.617021 (-560 1260);
PAINT ORANGE (-560 1260);
FORCEPROP 2 LASTPIN (-550 1300) $PN 223
J 2
(-560 1310);
DISPLAY 0.617021 (-560 1310);
PAINT ORANGE (-560 1310);
FORCEPROP 2 LASTPIN (-550 1350) $PN 220
J 2
(-560 1360);
DISPLAY 0.617021 (-560 1360);
PAINT ORANGE (-560 1360);
FORCEPROP 2 LASTPIN (-550 1400) $PN 217
J 2
(-560 1410);
DISPLAY 0.617021 (-560 1410);
PAINT ORANGE (-560 1410);
FORCEPROP 2 LASTPIN (-550 1450) $PN 215
J 2
(-560 1460);
DISPLAY 0.617021 (-560 1460);
PAINT ORANGE (-560 1460);
FORCEPROP 2 LASTPIN (-550 1500) $PN 212
J 2
(-560 1510);
DISPLAY 0.617021 (-560 1510);
PAINT ORANGE (-560 1510);
FORCEPROP 2 LASTPIN (-550 1550) $PN 209
J 2
(-560 1560);
DISPLAY 0.617021 (-560 1560);
PAINT ORANGE (-560 1560);
FORCEPROP 2 LASTPIN (-550 1600) $PN 206
J 2
(-560 1610);
DISPLAY 0.617021 (-560 1610);
PAINT ORANGE (-560 1610);
FORCEPROP 2 LASTPIN (-550 1650) $PN 204
J 2
(-560 1660);
DISPLAY 0.617021 (-560 1660);
PAINT ORANGE (-560 1660);
FORCEPROP 2 LASTPIN (-550 1700) $PN 92
J 2
(-560 1710);
DISPLAY 0.617021 (-560 1710);
PAINT ORANGE (-560 1710);
FORCEPROP 2 LASTPIN (-550 1750) $PN 90
J 2
(-560 1760);
DISPLAY 0.617021 (-560 1760);
PAINT ORANGE (-560 1760);
FORCEPROP 2 LASTPIN (-550 1800) $PN 88
J 2
(-560 1810);
DISPLAY 0.617021 (-560 1810);
PAINT ORANGE (-560 1810);
FORCEPROP 2 LASTPIN (-550 1850) $PN 85
J 2
(-560 1860);
DISPLAY 0.617021 (-560 1860);
PAINT ORANGE (-560 1860);
FORCEPROP 2 LASTPIN (-550 1900) $PN 83
J 2
(-560 1910);
DISPLAY 0.617021 (-560 1910);
PAINT ORANGE (-560 1910);
FORCEPROP 2 LASTPIN (-550 1950) $PN 80
J 2
(-560 1960);
DISPLAY 0.617021 (-560 1960);
PAINT ORANGE (-560 1960);
FORCEPROP 2 LASTPIN (-550 2000) $PN 76
J 2
(-560 2010);
DISPLAY 0.617021 (-560 2010);
PAINT ORANGE (-560 2010);
FORCEPROP 2 LASTPIN (-550 2050) $PN 73
J 2
(-560 2060);
DISPLAY 0.617021 (-560 2060);
PAINT ORANGE (-560 2060);
FORCEPROP 2 LASTPIN (-550 2100) $PN 70
J 2
(-560 2110);
DISPLAY 0.617021 (-560 2110);
PAINT ORANGE (-560 2110);
FORCEPROP 2 LASTPIN (-550 2150) $PN 67
J 2
(-560 2160);
DISPLAY 0.617021 (-560 2160);
PAINT ORANGE (-560 2160);
FORCEPROP 2 LASTPIN (-550 2200) $PN 64
J 2
(-560 2210);
DISPLAY 0.617021 (-560 2210);
PAINT ORANGE (-560 2210);
FORCEPROP 2 LASTPIN (-550 2250) $PN 61
J 2
(-560 2260);
DISPLAY 0.617021 (-560 2260);
PAINT ORANGE (-560 2260);
FORCEPROP 2 LASTPIN (-550 2300) $PN 59
J 2
(-560 2310);
DISPLAY 0.617021 (-560 2310);
PAINT ORANGE (-560 2310);
FORCEPROP 2 LASTPIN (-550 2550) $PN 287
J 2
(-560 2560);
DISPLAY 0.617021 (-560 2560);
PAINT ORANGE (-560 2560);
FORCEPROP 2 LASTPIN (-550 2600) $PN 286
J 2
(-560 2610);
DISPLAY 0.617021 (-560 2610);
PAINT ORANGE (-560 2610);
FORCEPROP 2 LASTPIN (-550 2650) $PN 288
J 2
(-560 2660);
DISPLAY 0.617021 (-560 2660);
PAINT ORANGE (-560 2660);
FORCEPROP 2 LASTPIN (-550 2700) $PN 143
J 2
(-560 2710);
DISPLAY 0.617021 (-560 2710);
PAINT ORANGE (-560 2710);
FORCEPROP 2 LASTPIN (-550 2750) $PN 142
J 2
(-560 2760);
DISPLAY 0.617021 (-560 2760);
PAINT ORANGE (-560 2760);
FORCEPROP 2 LASTPIN (-550 2400) $PN 221
J 2
(-560 2410);
DISPLAY 0.617021 (-560 2410);
PAINT ORANGE (-560 2410);
FORCEPROP 2 LASTPIN (-550 2450) $PN 77
J 2
(-560 2460);
DISPLAY 0.617021 (-560 2460);
PAINT ORANGE (-560 2460);
FORCEPROP 1 LAST MATERIAL SCONN
J 0
(-500 2950);
DISPLAY 0.617021 (-500 2950);
PAINT SKYBLUE (-500 2950);
FORCEPROP 1 LAST PART_NUMBER H44441-003
J 0
(-500 850);
DISPLAY 0.617021 (-500 850);
PAINT BLUE (-500 850);
FORCEPROP 1 LAST LOCATION J6L1
J 0
(-500 3000);
DISPLAY 0.617021 (-500 3000);
PAINT AQUA (-500 3000);
FORCEPROP 0 LAST BOM_SS NOPOP
J 0
(-275 2975);
DISPLAY 1.021277 (-275 2975);
PAINT BROWN (-275 2975);
DISPLAY BOTH (-275 2975);
FORCEPROP 2 LAST ROOM DDR4_CH_F1
J 0
(-50 1900);
PAINT ORANGE (-50 1900);
DISPLAY INVISIBLE (-50 1900);
FORCEPROP 1 LAST PATH I170
J 0
(-50 2950);
PAINT GREEN (-50 2950);
DISPLAY INVISIBLE (-50 2950);
FORCEPROP 2 LAST CDS_LOCATION J6L1
J 0
(-500 3000);
DISPLAY 0.617021 (-500 3000);
PAINT AQUA (-500 3000);
DISPLAY INVISIBLE (-500 3000);
FORCEPROP 2 LAST SEC 4
J 0
(-500 3050);
DISPLAY 0.680851 (-500 3050);
PAINT MONO (-500 3050);
DISPLAY INVISIBLE (-500 3050);
FORCEPROP 2 LAST SEC_TYPE PIP
J 0
(-500 3050);
DISPLAY 1.021277 (-500 3050);
PAINT ORANGE (-500 3050);
DISPLAY INVISIBLE (-500 3050);
FORCEPROP 2 LAST CDS_LIB mstr_sconn
J 0
(-50 1900);
PAINT ORANGE (-50 1900);
DISPLAY INVISIBLE (-50 1900);
FORCEPROP 2 LAST BOM_COST MEM
J 0
(-50 1900);
PAINT ORANGE (-50 1900);
DISPLAY INVISIBLE (-50 1900);
FORCEPROP 1 LAST PACK_TYPE PIP
J 0
(-500 3050);
PAINT SKYBLUE (-500 3050);
DISPLAY INVISIBLE (-500 3050);
FORCEADD GND..1
R 2
(2500 1250);
FORCEPROP 3 LASTPIN (2500 1300) SIG_NAME GND\g
J 0
(2510 1310);
DISPLAY 0.659574 (2510 1310);
PAINT MONO (2510 1310);
DISPLAY INVISIBLE (2510 1310);
FORCEPROP 1 LAST HDL_POWER GND
J 2
(2500 1400);
DISPLAY 0.553191 (2500 1400);
PAINT GREEN (2500 1400);
DISPLAY INVISIBLE (2500 1400);
FORCEPROP 2 LAST ROOM DDR4_CH_C
J 0
(2500 1255);
PAINT ORANGE (2500 1255);
DISPLAY INVISIBLE (2500 1255);
FORCEPROP 1 LAST PATH I171
J 2
(2425 1250);
DISPLAY 1.404255 (2425 1250);
PAINT GREEN (2425 1250);
DISPLAY INVISIBLE (2425 1250);
FORCEPROP 1 LAST BODY_TYPE PLUMBING
J 2
(2545 1207);
DISPLAY 0.340426 (2545 1207);
PAINT GREEN (2545 1207);
DISPLAY INVISIBLE (2545 1207);
FORCEPROP 2 LAST BOM_COST MEM
J 0
(2500 1255);
PAINT ORANGE (2500 1255);
DISPLAY INVISIBLE (2500 1255);
FORCEPROP 2 LAST CDS_LIB mstr_symbols
J 0
(2500 1250);
DISPLAY 0.787234 (2500 1250);
PAINT MONO (2500 1250);
DISPLAY INVISIBLE (2500 1250);
FORCEPROP 1 LAST SIZE 1B
J 2
(2425 1200);
DISPLAY 1.170213 (2425 1200);
PAINT GREEN (2425 1200);
DISPLAY INVISIBLE (2425 1200);
FORCEPROP 1 LAST VOLTAGE 0
J 0
(2500 1250);
PAINT SKYBLUE (2500 1250);
DISPLAY INVISIBLE (2500 1250);
FORCEADD OFFPAGE..1
(-3800 1700);
FORCEPROP 2 LAST $XR5 53 
J 0
(-4501 1700);
DISPLAY 0.638298 (-4501 1700);
PAINT MONO (-4501 1700);
FORCEPROP 2 LAST $XR4 52 
J 0
(-4411 1700);
DISPLAY 0.638298 (-4411 1700);
PAINT MONO (-4411 1700);
FORCEPROP 2 LAST $XR3 51 
J 0
(-4321 1700);
DISPLAY 0.638298 (-4321 1700);
PAINT MONO (-4321 1700);
FORCEPROP 2 LAST $XR2 50 
J 0
(-4231 1700);
DISPLAY 0.638298 (-4231 1700);
PAINT MONO (-4231 1700);
FORCEPROP 2 LAST $XR1 49 
J 0
(-4141 1700);
DISPLAY 0.638298 (-4141 1700);
PAINT MONO (-4141 1700);
FORCEPROP 2 LAST $XR0 99 
J 0
(-4051 1700);
DISPLAY 0.638298 (-4051 1700);
PAINT MONO (-4051 1700);
FORCEPROP 2 LAST PATH I172
J 0
(-4075 1750);
DISPLAY 0.787234 (-4075 1750);
PAINT ORANGE (-4075 1750);
DISPLAY INVISIBLE (-4075 1750);
FORCEPROP 1 LAST COMMENT_BODY TRUE
J 0
(-3675 1600);
DISPLAY 0.936170 (-3675 1600);
PAINT GREEN (-3675 1600);
DISPLAY INVISIBLE (-3675 1600);
FORCEPROP 1 LAST OFFPAGE TRUE
J 0
(-3475 1575);
DISPLAY 0.936170 (-3475 1575);
PAINT GREEN (-3475 1575);
DISPLAY INVISIBLE (-3475 1575);
FORCEPROP 2 LAST CDS_LIB mstr_standard
J 0
(-3800 1700);
DISPLAY 0.787234 (-3800 1700);
PAINT MONO (-3800 1700);
DISPLAY INVISIBLE (-3800 1700);
FORCEADD OFFPAGE..6
(-3800 1750);
FORCEPROP 2 LAST $XR5 99 
J 0
(-4499 1750);
DISPLAY 0.638298 (-4499 1750);
PAINT MONO (-4499 1750);
FORCEPROP 2 LAST $XR4 53 
J 0
(-4409 1750);
DISPLAY 0.638298 (-4409 1750);
PAINT MONO (-4409 1750);
FORCEPROP 2 LAST $XR3 52 
J 0
(-4319 1750);
DISPLAY 0.638298 (-4319 1750);
PAINT MONO (-4319 1750);
FORCEPROP 2 LAST $XR2 51 
J 0
(-4229 1750);
DISPLAY 0.638298 (-4229 1750);
PAINT MONO (-4229 1750);
FORCEPROP 2 LAST $XR1 50 
J 0
(-4139 1750);
DISPLAY 0.638298 (-4139 1750);
PAINT MONO (-4139 1750);
FORCEPROP 2 LAST $XR0 49 
J 0
(-4049 1750);
DISPLAY 0.638298 (-4049 1750);
PAINT MONO (-4049 1750);
FORCEPROP 2 LAST PATH I173
J 0
(-4125 1800);
DISPLAY 0.787234 (-4125 1800);
PAINT ORANGE (-4125 1800);
DISPLAY INVISIBLE (-4125 1800);
FORCEPROP 1 LAST COMMENT_BODY TRUE
J 0
(-3700 1675);
DISPLAY 0.936170 (-3700 1675);
PAINT GREEN (-3700 1675);
DISPLAY INVISIBLE (-3700 1675);
FORCEPROP 1 LAST OFFPAGE TRUE
J 0
(-3475 1625);
DISPLAY 0.936170 (-3475 1625);
PAINT GREEN (-3475 1625);
DISPLAY INVISIBLE (-3475 1625);
FORCEPROP 2 LAST CDS_LIB mstr_standard
J 0
(-3800 1750);
DISPLAY 0.787234 (-3800 1750);
PAINT MONO (-3800 1750);
DISPLAY INVISIBLE (-3800 1750);
FORCEADD OFFPAGE..1
(-4750 1600);
FORCEPROP 2 LAST $XR1 53 
J 0
(-5061 1600);
DISPLAY 0.638298 (-5061 1600);
PAINT MONO (-5061 1600);
FORCEPROP 2 LAST $XR0 98 
J 0
(-4971 1600);
DISPLAY 0.638298 (-4971 1600);
PAINT MONO (-4971 1600);
FORCEPROP 2 LAST PATH I174
J 0
(-5000 1650);
DISPLAY 0.787234 (-5000 1650);
PAINT ORANGE (-5000 1650);
DISPLAY INVISIBLE (-5000 1650);
FORCEPROP 1 LAST COMMENT_BODY TRUE
J 0
(-4625 1500);
DISPLAY 0.936170 (-4625 1500);
PAINT GREEN (-4625 1500);
DISPLAY INVISIBLE (-4625 1500);
FORCEPROP 1 LAST OFFPAGE TRUE
J 0
(-4425 1475);
DISPLAY 0.936170 (-4425 1475);
PAINT GREEN (-4425 1475);
DISPLAY INVISIBLE (-4425 1475);
FORCEPROP 2 LAST CDS_LIB mstr_standard
J 0
(-4750 1600);
DISPLAY 0.787234 (-4750 1600);
PAINT MONO (-4750 1600);
DISPLAY INVISIBLE (-4750 1600);
FORCEADD OFFPAGE..5
(-4125 2400);
FORCEPROP 2 LAST $XR23 94 
J 0
(-4739 2436);
DISPLAY 0.638298 (-4739 2436);
PAINT MONO (-4739 2436);
FORCEPROP 2 LAST $XR22 88 
J 0
(-4649 2436);
DISPLAY 0.638298 (-4649 2436);
PAINT MONO (-4649 2436);
FORCEPROP 2 LAST $XR21 87 
J 0
(-4559 2436);
DISPLAY 0.638298 (-4559 2436);
PAINT MONO (-4559 2436);
FORCEPROP 2 LAST $XR20 86 
J 0
(-4469 2436);
DISPLAY 0.638298 (-4469 2436);
PAINT MONO (-4469 2436);
FORCEPROP 2 LAST $XR19 85 
J 0
(-4379 2436);
DISPLAY 0.638298 (-4379 2436);
PAINT MONO (-4379 2436);
FORCEPROP 2 LAST $XR18 84 
J 0
(-5099 2364);
DISPLAY 0.638298 (-5099 2364);
PAINT MONO (-5099 2364);
FORCEPROP 2 LAST $XR17 83 
J 0
(-5009 2364);
DISPLAY 0.638298 (-5009 2364);
PAINT MONO (-5009 2364);
FORCEPROP 2 LAST $XR16 82 
J 0
(-4919 2364);
DISPLAY 0.638298 (-4919 2364);
PAINT MONO (-4919 2364);
FORCEPROP 2 LAST $XR15 81 
J 0
(-4829 2364);
DISPLAY 0.638298 (-4829 2364);
PAINT MONO (-4829 2364);
FORCEPROP 2 LAST $XR14 80 
J 0
(-4739 2364);
DISPLAY 0.638298 (-4739 2364);
PAINT MONO (-4739 2364);
FORCEPROP 2 LAST $XR13 79 
J 0
(-4649 2364);
DISPLAY 0.638298 (-4649 2364);
PAINT MONO (-4649 2364);
FORCEPROP 2 LAST $XR12 78 
J 0
(-4559 2364);
DISPLAY 0.638298 (-4559 2364);
PAINT MONO (-4559 2364);
FORCEPROP 2 LAST $XR11 77 
J 0
(-4469 2364);
DISPLAY 0.638298 (-4469 2364);
PAINT MONO (-4469 2364);
FORCEPROP 2 LAST $XR10 53 
J 0
(-4379 2364);
DISPLAY 0.638298 (-4379 2364);
PAINT MONO (-4379 2364);
FORCEPROP 2 LAST $XR9 52 
J 0
(-5189 2400);
DISPLAY 0.638298 (-5189 2400);
PAINT MONO (-5189 2400);
FORCEPROP 2 LAST $XR8 51 
J 0
(-5099 2400);
DISPLAY 0.638298 (-5099 2400);
PAINT MONO (-5099 2400);
FORCEPROP 2 LAST $XR7 50 
J 0
(-5009 2400);
DISPLAY 0.638298 (-5009 2400);
PAINT MONO (-5009 2400);
FORCEPROP 2 LAST $XR6 49 
J 0
(-4919 2400);
DISPLAY 0.638298 (-4919 2400);
PAINT MONO (-4919 2400);
FORCEPROP 2 LAST $XR5 48 
J 0
(-4829 2400);
DISPLAY 0.638298 (-4829 2400);
PAINT MONO (-4829 2400);
FORCEPROP 2 LAST $XR4 47 
J 0
(-4739 2400);
DISPLAY 0.638298 (-4739 2400);
PAINT MONO (-4739 2400);
FORCEPROP 2 LAST $XR3 46 
J 0
(-4649 2400);
DISPLAY 0.638298 (-4649 2400);
PAINT MONO (-4649 2400);
FORCEPROP 2 LAST $XR2 45 
J 0
(-4559 2400);
DISPLAY 0.638298 (-4559 2400);
PAINT MONO (-4559 2400);
FORCEPROP 2 LAST $XR1 44 
J 0
(-4469 2400);
DISPLAY 0.638298 (-4469 2400);
PAINT MONO (-4469 2400);
FORCEPROP 2 LAST $XR0 43 
J 0
(-4379 2400);
DISPLAY 0.638298 (-4379 2400);
PAINT MONO (-4379 2400);
FORCEPROP 2 LAST PATH I175
J 0
(-4075 2475);
DISPLAY 0.787234 (-4075 2475);
PAINT ORANGE (-4075 2475);
DISPLAY INVISIBLE (-4075 2475);
FORCEPROP 1 LAST COMMENT_BODY TRUE
J 0
(-4025 2325);
DISPLAY 1.404255 (-4025 2325);
PAINT GREEN (-4025 2325);
DISPLAY INVISIBLE (-4025 2325);
FORCEPROP 1 LAST OFFPAGE TRUE
J 0
(-3800 2275);
DISPLAY 1.404255 (-3800 2275);
PAINT GREEN (-3800 2275);
DISPLAY INVISIBLE (-3800 2275);
FORCEPROP 2 LAST CDS_LIB mstr_standard
J 0
(-4125 2400);
DISPLAY 0.787234 (-4125 2400);
PAINT MONO (-4125 2400);
DISPLAY INVISIBLE (-4125 2400);
FORCEADD GND..1
(-4600 1150);
FORCEPROP 3 LASTPIN (-4600 1200) SIG_NAME GND\g
J 0
(-4590 1210);
DISPLAY 0.659574 (-4590 1210);
PAINT MONO (-4590 1210);
DISPLAY INVISIBLE (-4590 1210);
FORCEPROP 1 LAST HDL_POWER GND
J 0
(-4600 1300);
DISPLAY 1.404255 (-4600 1300);
PAINT GREEN (-4600 1300);
DISPLAY INVISIBLE (-4600 1300);
FORCEPROP 2 LAST ROOM DDR4_CH_C
J 0
(-4600 1155);
PAINT ORANGE (-4600 1155);
DISPLAY INVISIBLE (-4600 1155);
FORCEPROP 1 LAST PATH I178
J 0
(-4525 1150);
DISPLAY 1.404255 (-4525 1150);
PAINT GREEN (-4525 1150);
DISPLAY INVISIBLE (-4525 1150);
FORCEPROP 1 LAST BODY_TYPE PLUMBING
J 0
(-4645 1107);
DISPLAY 0.340426 (-4645 1107);
PAINT GREEN (-4645 1107);
DISPLAY INVISIBLE (-4645 1107);
FORCEPROP 1 LAST SIZE 1B
J 0
(-4525 1100);
DISPLAY 1.787234 (-4525 1100);
PAINT GREEN (-4525 1100);
DISPLAY INVISIBLE (-4525 1100);
FORCEPROP 2 LAST BOM_COST MEM
J 0
(-4600 1155);
PAINT ORANGE (-4600 1155);
DISPLAY INVISIBLE (-4600 1155);
FORCEPROP 2 LAST CDS_LIB mstr_symbols
J 0
(-4600 1150);
PAINT ORANGE (-4600 1150);
DISPLAY INVISIBLE (-4600 1150);
FORCEPROP 1 LAST VOLTAGE 0
J 0
(-4600 1150);
PAINT SKYBLUE (-4600 1150);
DISPLAY INVISIBLE (-4600 1150);
FORCEADD CAP_A..1
R 2
(-4600 1400);
FORCEPROP 1 LAST LOCATION C4A5
J 2
(-4650 1500);
DISPLAY 0.617021 (-4650 1500);
PAINT AQUA (-4650 1500);
FORCEPROP 1 LAST VALUE 0.01UF
J 2
(-4650 1450);
DISPLAY 0.617021 (-4650 1450);
PAINT SKYBLUE (-4650 1450);
FORCEPROP 1 LAST VOLTAGE 25V
J 2
(-4650 1400);
DISPLAY 0.617021 (-4650 1400);
PAINT SKYBLUE (-4650 1400);
FORCEPROP 1 LASTPIN (-4600 1500) $PN 1
J 2
(-4610 1480);
DISPLAY 0.787234 (-4610 1480);
PAINT ORANGE (-4610 1480);
FORCEPROP 1 LASTPIN (-4600 1300) $PN 2
J 2
(-4610 1280);
DISPLAY 0.787234 (-4610 1280);
PAINT ORANGE (-4610 1280);
FORCEPROP 1 LAST PACK_TYPE 0402V
J 2
(-4650 1200);
DISPLAY 0.617021 (-4650 1200);
PAINT SKYBLUE (-4650 1200);
FORCEPROP 1 LAST MATERIAL X7R
J 2
(-4650 1300);
DISPLAY 0.617021 (-4650 1300);
PAINT SKYBLUE (-4650 1300);
FORCEPROP 1 LAST TOLERANCE 10%
J 2
(-4650 1350);
DISPLAY 0.617021 (-4650 1350);
PAINT SKYBLUE (-4650 1350);
FORCEPROP 1 LAST PART_NUMBER A36096-045
J 2
(-4650 1250);
DISPLAY 0.617021 (-4650 1250);
PAINT BLUE (-4650 1250);
FORCEPROP 2 LAST SEC_TYPE 0402V
J 0
(-4650 1600);
DISPLAY 1.021277 (-4650 1600);
PAINT ORANGE (-4650 1600);
DISPLAY INVISIBLE (-4650 1600);
FORCEPROP 2 LAST SEC 1
J 0
(-4650 1600);
PAINT MONO (-4650 1600);
DISPLAY INVISIBLE (-4650 1600);
FORCEPROP 2 LAST ROOM DDR4_CH_F1
J 0
(-4600 1400);
PAINT ORANGE (-4600 1400);
DISPLAY INVISIBLE (-4600 1400);
FORCEPROP 1 LAST PATH I179
J 2
(-4650 1550);
DISPLAY 0.978723 (-4650 1550);
PAINT WHITE (-4650 1550);
DISPLAY INVISIBLE (-4650 1550);
FORCEPROP 2 LAST CDS_LIB dev_discrete
J 0
(-4600 1400);
PAINT ORANGE (-4600 1400);
DISPLAY INVISIBLE (-4600 1400);
FORCEPROP 2 LAST BOM_COST MEM
J 0
(-4600 1400);
PAINT ORANGE (-4600 1400);
DISPLAY INVISIBLE (-4600 1400);
FORCEPROP 2 LAST CDS_LOCATION C4A5
J 2
(-4650 1500);
DISPLAY 0.617021 (-4650 1500);
PAINT AQUA (-4650 1500);
DISPLAY INVISIBLE (-4650 1500);
FORCEADD PVPP_DEF..1
(-750 2900);
FORCEPROP 3 LASTPIN (-750 2850) SIG_NAME PVPP_DEF\g
J 0
(-740 2860);
DISPLAY 0.659574 (-740 2860);
PAINT MONO (-740 2860);
DISPLAY INVISIBLE (-740 2860);
FORCEPROP 1 LAST HDL_POWER PVPP_DEF
J 1
(-750 2950);
DISPLAY 0.872340 (-750 2950);
PAINT GREEN (-750 2950);
DISPLAY INVISIBLE (-750 2950);
FORCEPROP 2 LAST ROOM DDR4_CH_C
J 0
(-750 3000);
PAINT ORANGE (-750 3000);
DISPLAY INVISIBLE (-750 3000);
FORCEPROP 1 LAST PATH I180
J 0
(-700 2925);
DISPLAY 0.872340 (-700 2925);
PAINT AQUA (-700 2925);
DISPLAY INVISIBLE (-700 2925);
FORCEPROP 1 LAST BODY_TYPE PLUMBING
J 0
(-795 2857);
DISPLAY 0.340426 (-795 2857);
PAINT GREEN (-795 2857);
DISPLAY INVISIBLE (-795 2857);
FORCEPROP 2 LAST CDS_LIB mstr_symbols
J 0
(-750 2900);
PAINT ORANGE (-750 2900);
DISPLAY INVISIBLE (-750 2900);
FORCEPROP 0 LAST BOM_COST MEM
J 0
(-750 3000);
PAINT ORANGE (-750 3000);
DISPLAY INVISIBLE (-750 3000);
FORCEPROP 1 LAST VOLTAGE 2.5V
J 0
(-795 2857);
DISPLAY 0.340426 (-795 2857);
PAINT SKYBLUE (-795 2857);
DISPLAY INVISIBLE (-795 2857);
FORCEADD PVPP_DEF..1
(-5200 2100);
FORCEPROP 3 LASTPIN (-5200 2050) SIG_NAME PVPP_DEF\g
J 0
(-5190 2060);
DISPLAY 0.659574 (-5190 2060);
PAINT MONO (-5190 2060);
DISPLAY INVISIBLE (-5190 2060);
FORCEPROP 1 LAST HDL_POWER PVPP_DEF
J 1
(-5200 2150);
DISPLAY 0.872340 (-5200 2150);
PAINT GREEN (-5200 2150);
DISPLAY INVISIBLE (-5200 2150);
FORCEPROP 2 LAST ROOM DDR4_CH_C
J 0
(-5200 2200);
PAINT ORANGE (-5200 2200);
DISPLAY INVISIBLE (-5200 2200);
FORCEPROP 1 LAST PATH I181
J 0
(-5150 2125);
DISPLAY 0.872340 (-5150 2125);
PAINT AQUA (-5150 2125);
DISPLAY INVISIBLE (-5150 2125);
FORCEPROP 1 LAST BODY_TYPE PLUMBING
J 0
(-5245 2057);
DISPLAY 0.340426 (-5245 2057);
PAINT GREEN (-5245 2057);
DISPLAY INVISIBLE (-5245 2057);
FORCEPROP 2 LAST CDS_LIB mstr_symbols
J 0
(-5200 2100);
PAINT ORANGE (-5200 2100);
DISPLAY INVISIBLE (-5200 2100);
FORCEPROP 0 LAST BOM_COST MEM
J 0
(-5200 2200);
PAINT ORANGE (-5200 2200);
DISPLAY INVISIBLE (-5200 2200);
FORCEPROP 1 LAST VOLTAGE 2.5V
J 0
(-5245 2057);
DISPLAY 0.340426 (-5245 2057);
PAINT SKYBLUE (-5245 2057);
DISPLAY INVISIBLE (-5245 2057);
FORCEADD OFFPAGE..1
(-3800 1300);
FORCEPROP 2 LAST $XR5 53 
J 0
(-4501 1300);
DISPLAY 0.638298 (-4501 1300);
PAINT MONO (-4501 1300);
FORCEPROP 2 LAST $XR4 52 
J 0
(-4411 1300);
DISPLAY 0.638298 (-4411 1300);
PAINT MONO (-4411 1300);
FORCEPROP 2 LAST $XR3 51 
J 0
(-4321 1300);
DISPLAY 0.638298 (-4321 1300);
PAINT MONO (-4321 1300);
FORCEPROP 2 LAST $XR2 50 
J 0
(-4231 1300);
DISPLAY 0.638298 (-4231 1300);
PAINT MONO (-4231 1300);
FORCEPROP 2 LAST $XR1 49 
J 0
(-4141 1300);
DISPLAY 0.638298 (-4141 1300);
PAINT MONO (-4141 1300);
FORCEPROP 2 LAST $XR0 89 
J 0
(-4051 1300);
DISPLAY 0.638298 (-4051 1300);
PAINT MONO (-4051 1300);
FORCEPROP 2 LAST PATH I182
J 0
(-3750 1375);
PAINT ORANGE (-3750 1375);
DISPLAY INVISIBLE (-3750 1375);
FORCEPROP 1 LAST COMMENT_BODY TRUE
J 0
(-3675 1200);
DISPLAY 0.936170 (-3675 1200);
PAINT GREEN (-3675 1200);
DISPLAY INVISIBLE (-3675 1200);
FORCEPROP 1 LAST OFFPAGE TRUE
J 0
(-3475 1175);
DISPLAY 0.936170 (-3475 1175);
PAINT GREEN (-3475 1175);
DISPLAY INVISIBLE (-3475 1175);
FORCEPROP 2 LAST CDS_LIB mstr_standard
J 0
(-3800 1300);
PAINT ORANGE (-3800 1300);
DISPLAY INVISIBLE (-3800 1300);
FORCEADD GND..1
(-5200 1750);
FORCEPROP 3 LASTPIN (-5200 1800) SIG_NAME GND\g
J 0
(-5190 1810);
DISPLAY 0.659574 (-5190 1810);
PAINT MONO (-5190 1810);
DISPLAY INVISIBLE (-5190 1810);
FORCEPROP 1 LAST HDL_POWER GND
J 0
(-5200 1900);
DISPLAY 1.404255 (-5200 1900);
PAINT GREEN (-5200 1900);
DISPLAY INVISIBLE (-5200 1900);
FORCEPROP 2 LAST ROOM DDR4_CH_C
J 0
(-5200 1755);
PAINT ORANGE (-5200 1755);
DISPLAY INVISIBLE (-5200 1755);
FORCEPROP 1 LAST PATH I186
J 0
(-5125 1750);
DISPLAY 0.872340 (-5125 1750);
PAINT AQUA (-5125 1750);
DISPLAY INVISIBLE (-5125 1750);
FORCEPROP 1 LAST BODY_TYPE PLUMBING
J 0
(-5245 1707);
DISPLAY 0.340426 (-5245 1707);
PAINT GREEN (-5245 1707);
DISPLAY INVISIBLE (-5245 1707);
FORCEPROP 2 LAST CDS_LIB mstr_symbols
J 0
(-5200 1750);
PAINT ORANGE (-5200 1750);
DISPLAY INVISIBLE (-5200 1750);
FORCEPROP 2 LAST BOM_COST MEM
J 0
(-5200 1755);
PAINT ORANGE (-5200 1755);
DISPLAY INVISIBLE (-5200 1755);
FORCEPROP 1 LAST SIZE 1B
J 0
(-5125 1700);
DISPLAY 1.787234 (-5125 1700);
PAINT GREEN (-5125 1700);
DISPLAY INVISIBLE (-5125 1700);
FORCEPROP 1 LAST VOLTAGE 0
J 0
(-5200 1750);
PAINT SKYBLUE (-5200 1750);
DISPLAY INVISIBLE (-5200 1750);
FORCEADD P12V_NVDIMM_DEF..1
(650 2975);
FORCEPROP 3 LASTPIN (650 2925) SIG_NAME P12V_NVDIMM_DEF\g
J 0
(660 2935);
DISPLAY 0.659574 (660 2935);
PAINT MONO (660 2935);
DISPLAY INVISIBLE (660 2935);
FORCEPROP 1 LAST HDL_POWER P12V_NVDIMM_DEF
J 1
(650 3025);
DISPLAY 0.872340 (650 3025);
PAINT GREEN (650 3025);
DISPLAY INVISIBLE (650 3025);
FORCEPROP 1 LAST PATH I187
J 0
(700 3000);
DISPLAY 0.872340 (700 3000);
PAINT AQUA (700 3000);
DISPLAY INVISIBLE (700 3000);
FORCEPROP 1 LAST BODY_TYPE PLUMBING
J 0
(605 2932);
DISPLAY 0.340426 (605 2932);
PAINT GREEN (605 2932);
DISPLAY INVISIBLE (605 2932);
FORCEPROP 2 LAST CDS_LIB mstr_symbols
J 0
(650 2975);
PAINT ORANGE (650 2975);
DISPLAY INVISIBLE (650 2975);
FORCEPROP 1 LAST VOLTAGE 12.0
J 0
(605 2932);
DISPLAY 0.340426 (605 2932);
PAINT SKYBLUE (605 2932);
DISPLAY INVISIBLE (605 2932);
FORCEADD TAP..6
R 2
(900 4500);
FORCEPROP 3 LASTPIN (850 4500) SIG_NAME M_F_DQS_DN<11>
J 0
(860 4510);
DISPLAY 0.659574 (860 4510);
PAINT MONO (860 4510);
DISPLAY INVISIBLE (860 4510);
FORCEPROP 1 LASTPIN (850 4500) BN 11
J 2
(900 4510);
DISPLAY 0.617021 (900 4510);
PAINT PINK (900 4510);
FORCEPROP 1 LAST PATH I19
J 2
(900 4500);
DISPLAY 0.936170 (900 4500);
PAINT GREEN (900 4500);
DISPLAY INVISIBLE (900 4500);
FORCEPROP 1 LAST HDL_TAP TRUE
J 2
(575 4375);
DISPLAY 1.234043 (575 4375);
PAINT GREEN (575 4375);
DISPLAY INVISIBLE (575 4375);
FORCEPROP 1 LAST BODY_TYPE PLUMBING
J 2
(900 4450);
DISPLAY 1.234043 (900 4450);
PAINT GREEN (900 4450);
DISPLAY INVISIBLE (900 4450);
FORCEPROP 2 LAST CDS_LIB mstr_standard
J 0
(900 4500);
DISPLAY 0.787234 (900 4500);
PAINT MONO (900 4500);
DISPLAY INVISIBLE (900 4500);
FORCEADD OFFPAGE..3
(1575 5150);
FORCEPROP 2 LAST $XR1 53 
J 0
(1879 5150);
DISPLAY 0.638298 (1879 5150);
PAINT MONO (1879 5150);
FORCEPROP 2 LAST $XR0 28 
J 0
(1789 5150);
DISPLAY 0.638298 (1789 5150);
PAINT MONO (1789 5150);
FORCEPROP 2 LAST PATH I2
J 0
(1775 5225);
DISPLAY 0.787234 (1775 5225);
PAINT MONO (1775 5225);
DISPLAY INVISIBLE (1775 5225);
FORCEPROP 1 LAST COMMENT_BODY TRUE
J 0
(1525 5050);
DISPLAY 0.936170 (1525 5050);
PAINT GREEN (1525 5050);
DISPLAY INVISIBLE (1525 5050);
FORCEPROP 1 LAST OFFPAGE TRUE
J 0
(1900 5025);
DISPLAY 0.936170 (1900 5025);
PAINT GREEN (1900 5025);
DISPLAY INVISIBLE (1900 5025);
FORCEPROP 2 LAST CDS_LIB mstr_standard
J 0
(1575 5150);
DISPLAY 0.787234 (1575 5150);
PAINT MONO (1575 5150);
DISPLAY INVISIBLE (1575 5150);
FORCEADD TAP..6
R 2
(900 4400);
FORCEPROP 3 LASTPIN (850 4400) SIG_NAME M_F_DQS_DN<10>
J 0
(860 4410);
DISPLAY 0.659574 (860 4410);
PAINT MONO (860 4410);
DISPLAY INVISIBLE (860 4410);
FORCEPROP 1 LASTPIN (850 4400) BN 10
J 2
(900 4410);
DISPLAY 0.617021 (900 4410);
PAINT PINK (900 4410);
FORCEPROP 1 LAST PATH I20
J 2
(900 4400);
DISPLAY 0.936170 (900 4400);
PAINT GREEN (900 4400);
DISPLAY INVISIBLE (900 4400);
FORCEPROP 1 LAST HDL_TAP TRUE
J 2
(575 4275);
DISPLAY 1.234043 (575 4275);
PAINT GREEN (575 4275);
DISPLAY INVISIBLE (575 4275);
FORCEPROP 1 LAST BODY_TYPE PLUMBING
J 2
(900 4350);
DISPLAY 1.234043 (900 4350);
PAINT GREEN (900 4350);
DISPLAY INVISIBLE (900 4350);
FORCEPROP 2 LAST CDS_LIB mstr_standard
J 0
(900 4400);
DISPLAY 0.787234 (900 4400);
PAINT MONO (900 4400);
DISPLAY INVISIBLE (900 4400);
FORCEADD TAP..6
R 2
(900 4300);
FORCEPROP 3 LASTPIN (850 4300) SIG_NAME M_F_DQS_DN<9>
J 0
(860 4310);
DISPLAY 0.659574 (860 4310);
PAINT MONO (860 4310);
DISPLAY INVISIBLE (860 4310);
FORCEPROP 1 LASTPIN (850 4300) BN 9
J 2
(900 4310);
DISPLAY 0.617021 (900 4310);
PAINT PINK (900 4310);
FORCEPROP 1 LAST PATH I21
J 2
(900 4300);
DISPLAY 0.936170 (900 4300);
PAINT GREEN (900 4300);
DISPLAY INVISIBLE (900 4300);
FORCEPROP 1 LAST HDL_TAP TRUE
J 2
(575 4175);
DISPLAY 1.234043 (575 4175);
PAINT GREEN (575 4175);
DISPLAY INVISIBLE (575 4175);
FORCEPROP 1 LAST BODY_TYPE PLUMBING
J 2
(900 4250);
DISPLAY 1.234043 (900 4250);
PAINT GREEN (900 4250);
DISPLAY INVISIBLE (900 4250);
FORCEPROP 2 LAST CDS_LIB mstr_standard
J 0
(900 4300);
DISPLAY 0.787234 (900 4300);
PAINT MONO (900 4300);
DISPLAY INVISIBLE (900 4300);
FORCEADD TAP..6
R 2
(900 4200);
FORCEPROP 3 LASTPIN (850 4200) SIG_NAME M_F_DQS_DN<8>
J 0
(860 4210);
DISPLAY 0.659574 (860 4210);
PAINT MONO (860 4210);
DISPLAY INVISIBLE (860 4210);
FORCEPROP 1 LASTPIN (850 4200) BN 8
J 2
(900 4210);
DISPLAY 0.617021 (900 4210);
PAINT PINK (900 4210);
FORCEPROP 1 LAST PATH I22
J 2
(900 4200);
DISPLAY 0.936170 (900 4200);
PAINT GREEN (900 4200);
DISPLAY INVISIBLE (900 4200);
FORCEPROP 1 LAST HDL_TAP TRUE
J 2
(575 4075);
DISPLAY 1.234043 (575 4075);
PAINT GREEN (575 4075);
DISPLAY INVISIBLE (575 4075);
FORCEPROP 1 LAST BODY_TYPE PLUMBING
J 2
(900 4150);
DISPLAY 1.234043 (900 4150);
PAINT GREEN (900 4150);
DISPLAY INVISIBLE (900 4150);
FORCEPROP 2 LAST CDS_LIB mstr_standard
J 0
(900 4200);
DISPLAY 0.787234 (900 4200);
PAINT MONO (900 4200);
DISPLAY INVISIBLE (900 4200);
FORCEADD TAP..6
R 2
(900 4100);
FORCEPROP 3 LASTPIN (850 4100) SIG_NAME M_F_DQS_DN<7>
J 0
(860 4110);
DISPLAY 0.659574 (860 4110);
PAINT MONO (860 4110);
DISPLAY INVISIBLE (860 4110);
FORCEPROP 1 LASTPIN (850 4100) BN 7
J 2
(900 4110);
DISPLAY 0.617021 (900 4110);
PAINT PINK (900 4110);
FORCEPROP 1 LAST PATH I23
J 2
(900 4100);
DISPLAY 0.936170 (900 4100);
PAINT GREEN (900 4100);
DISPLAY INVISIBLE (900 4100);
FORCEPROP 1 LAST HDL_TAP TRUE
J 2
(575 3975);
DISPLAY 1.234043 (575 3975);
PAINT GREEN (575 3975);
DISPLAY INVISIBLE (575 3975);
FORCEPROP 1 LAST BODY_TYPE PLUMBING
J 2
(900 4050);
DISPLAY 1.234043 (900 4050);
PAINT GREEN (900 4050);
DISPLAY INVISIBLE (900 4050);
FORCEPROP 2 LAST CDS_LIB mstr_standard
J 0
(900 4100);
DISPLAY 0.787234 (900 4100);
PAINT MONO (900 4100);
DISPLAY INVISIBLE (900 4100);
FORCEADD TAP..6
R 2
(700 4450);
FORCEPROP 3 LASTPIN (650 4450) SIG_NAME M_F_DQS_DP<10>
J 0
(660 4460);
DISPLAY 0.659574 (660 4460);
PAINT MONO (660 4460);
DISPLAY INVISIBLE (660 4460);
FORCEPROP 1 LASTPIN (650 4450) BN 10
J 2
(700 4460);
DISPLAY 0.617021 (700 4460);
PAINT PINK (700 4460);
FORCEPROP 1 LAST PATH I24
J 2
(700 4450);
DISPLAY 0.936170 (700 4450);
PAINT GREEN (700 4450);
DISPLAY INVISIBLE (700 4450);
FORCEPROP 1 LAST HDL_TAP TRUE
J 2
(375 4325);
DISPLAY 1.234043 (375 4325);
PAINT GREEN (375 4325);
DISPLAY INVISIBLE (375 4325);
FORCEPROP 1 LAST BODY_TYPE PLUMBING
J 2
(700 4400);
DISPLAY 1.234043 (700 4400);
PAINT GREEN (700 4400);
DISPLAY INVISIBLE (700 4400);
FORCEPROP 2 LAST CDS_LIB mstr_standard
J 0
(700 4450);
DISPLAY 0.787234 (700 4450);
PAINT MONO (700 4450);
DISPLAY INVISIBLE (700 4450);
FORCEADD TAP..6
R 2
(700 4350);
FORCEPROP 3 LASTPIN (650 4350) SIG_NAME M_F_DQS_DP<9>
J 0
(660 4360);
DISPLAY 0.659574 (660 4360);
PAINT MONO (660 4360);
DISPLAY INVISIBLE (660 4360);
FORCEPROP 1 LASTPIN (650 4350) BN 9
J 2
(700 4360);
DISPLAY 0.617021 (700 4360);
PAINT PINK (700 4360);
FORCEPROP 1 LAST PATH I25
J 2
(700 4350);
DISPLAY 0.936170 (700 4350);
PAINT GREEN (700 4350);
DISPLAY INVISIBLE (700 4350);
FORCEPROP 1 LAST HDL_TAP TRUE
J 2
(375 4225);
DISPLAY 1.234043 (375 4225);
PAINT GREEN (375 4225);
DISPLAY INVISIBLE (375 4225);
FORCEPROP 1 LAST BODY_TYPE PLUMBING
J 2
(700 4300);
DISPLAY 1.234043 (700 4300);
PAINT GREEN (700 4300);
DISPLAY INVISIBLE (700 4300);
FORCEPROP 2 LAST CDS_LIB mstr_standard
J 0
(700 4350);
DISPLAY 0.787234 (700 4350);
PAINT MONO (700 4350);
DISPLAY INVISIBLE (700 4350);
FORCEADD TAP..6
R 2
(700 4050);
FORCEPROP 3 LASTPIN (650 4050) SIG_NAME M_F_DQS_DP<6>
J 0
(660 4060);
DISPLAY 0.659574 (660 4060);
PAINT MONO (660 4060);
DISPLAY INVISIBLE (660 4060);
FORCEPROP 1 LASTPIN (650 4050) BN 6
J 2
(700 4060);
DISPLAY 0.617021 (700 4060);
PAINT PINK (700 4060);
FORCEPROP 1 LAST PATH I26
J 2
(700 4050);
DISPLAY 0.936170 (700 4050);
PAINT GREEN (700 4050);
DISPLAY INVISIBLE (700 4050);
FORCEPROP 1 LAST HDL_TAP TRUE
J 2
(375 3925);
DISPLAY 1.234043 (375 3925);
PAINT GREEN (375 3925);
DISPLAY INVISIBLE (375 3925);
FORCEPROP 1 LAST BODY_TYPE PLUMBING
J 2
(700 4000);
DISPLAY 1.234043 (700 4000);
PAINT GREEN (700 4000);
DISPLAY INVISIBLE (700 4000);
FORCEPROP 2 LAST CDS_LIB mstr_standard
J 0
(700 4050);
DISPLAY 0.787234 (700 4050);
PAINT MONO (700 4050);
DISPLAY INVISIBLE (700 4050);
FORCEADD TAP..6
R 2
(700 4150);
FORCEPROP 3 LASTPIN (650 4150) SIG_NAME M_F_DQS_DP<7>
J 0
(660 4160);
DISPLAY 0.659574 (660 4160);
PAINT MONO (660 4160);
DISPLAY INVISIBLE (660 4160);
FORCEPROP 1 LASTPIN (650 4150) BN 7
J 2
(700 4160);
DISPLAY 0.617021 (700 4160);
PAINT PINK (700 4160);
FORCEPROP 1 LAST PATH I27
J 2
(700 4150);
DISPLAY 0.936170 (700 4150);
PAINT GREEN (700 4150);
DISPLAY INVISIBLE (700 4150);
FORCEPROP 1 LAST HDL_TAP TRUE
J 2
(375 4025);
DISPLAY 1.234043 (375 4025);
PAINT GREEN (375 4025);
DISPLAY INVISIBLE (375 4025);
FORCEPROP 1 LAST BODY_TYPE PLUMBING
J 2
(700 4100);
DISPLAY 1.234043 (700 4100);
PAINT GREEN (700 4100);
DISPLAY INVISIBLE (700 4100);
FORCEPROP 2 LAST CDS_LIB mstr_standard
J 0
(700 4150);
DISPLAY 0.787234 (700 4150);
PAINT MONO (700 4150);
DISPLAY INVISIBLE (700 4150);
FORCEADD TAP..6
R 2
(700 4250);
FORCEPROP 3 LASTPIN (650 4250) SIG_NAME M_F_DQS_DP<8>
J 0
(660 4260);
DISPLAY 0.659574 (660 4260);
PAINT MONO (660 4260);
DISPLAY INVISIBLE (660 4260);
FORCEPROP 1 LASTPIN (650 4250) BN 8
J 2
(700 4260);
DISPLAY 0.617021 (700 4260);
PAINT PINK (700 4260);
FORCEPROP 1 LAST PATH I28
J 2
(700 4250);
DISPLAY 0.936170 (700 4250);
PAINT GREEN (700 4250);
DISPLAY INVISIBLE (700 4250);
FORCEPROP 1 LAST HDL_TAP TRUE
J 2
(375 4125);
DISPLAY 1.234043 (375 4125);
PAINT GREEN (375 4125);
DISPLAY INVISIBLE (375 4125);
FORCEPROP 1 LAST BODY_TYPE PLUMBING
J 2
(700 4200);
DISPLAY 1.234043 (700 4200);
PAINT GREEN (700 4200);
DISPLAY INVISIBLE (700 4200);
FORCEPROP 2 LAST CDS_LIB mstr_standard
J 0
(700 4250);
DISPLAY 0.787234 (700 4250);
PAINT MONO (700 4250);
DISPLAY INVISIBLE (700 4250);
FORCEADD TAP..6
R 2
(900 4000);
FORCEPROP 3 LASTPIN (850 4000) SIG_NAME M_F_DQS_DN<6>
J 0
(860 4010);
DISPLAY 0.659574 (860 4010);
PAINT MONO (860 4010);
DISPLAY INVISIBLE (860 4010);
FORCEPROP 1 LASTPIN (850 4000) BN 6
J 2
(900 4010);
DISPLAY 0.617021 (900 4010);
PAINT PINK (900 4010);
FORCEPROP 1 LAST PATH I29
J 2
(900 4000);
DISPLAY 0.936170 (900 4000);
PAINT GREEN (900 4000);
DISPLAY INVISIBLE (900 4000);
FORCEPROP 1 LAST HDL_TAP TRUE
J 2
(575 3875);
DISPLAY 1.234043 (575 3875);
PAINT GREEN (575 3875);
DISPLAY INVISIBLE (575 3875);
FORCEPROP 1 LAST BODY_TYPE PLUMBING
J 2
(900 3950);
DISPLAY 1.234043 (900 3950);
PAINT GREEN (900 3950);
DISPLAY INVISIBLE (900 3950);
FORCEPROP 2 LAST CDS_LIB mstr_standard
J 0
(900 4000);
DISPLAY 0.787234 (900 4000);
PAINT MONO (900 4000);
DISPLAY INVISIBLE (900 4000);
FORCEADD TAP..6
R 2
(900 5100);
FORCEPROP 3 LASTPIN (850 5100) SIG_NAME M_F_DQS_DN<17>
J 0
(860 5110);
DISPLAY 0.659574 (860 5110);
PAINT MONO (860 5110);
DISPLAY INVISIBLE (860 5110);
FORCEPROP 1 LASTPIN (850 5100) BN 17
J 2
(900 5110);
DISPLAY 0.617021 (900 5110);
PAINT PINK (900 5110);
FORCEPROP 1 LAST PATH I3
J 2
(900 5100);
DISPLAY 0.936170 (900 5100);
PAINT GREEN (900 5100);
DISPLAY INVISIBLE (900 5100);
FORCEPROP 1 LAST HDL_TAP TRUE
J 2
(575 4975);
DISPLAY 1.234043 (575 4975);
PAINT GREEN (575 4975);
DISPLAY INVISIBLE (575 4975);
FORCEPROP 1 LAST BODY_TYPE PLUMBING
J 2
(900 5050);
DISPLAY 1.234043 (900 5050);
PAINT GREEN (900 5050);
DISPLAY INVISIBLE (900 5050);
FORCEPROP 2 LAST CDS_LIB mstr_standard
J 2
(900 5100);
DISPLAY 0.787234 (900 5100);
PAINT MONO (900 5100);
DISPLAY INVISIBLE (900 5100);
FORCEADD TAP..6
R 2
(900 3900);
FORCEPROP 3 LASTPIN (850 3900) SIG_NAME M_F_DQS_DN<5>
J 0
(860 3910);
DISPLAY 0.659574 (860 3910);
PAINT MONO (860 3910);
DISPLAY INVISIBLE (860 3910);
FORCEPROP 1 LASTPIN (850 3900) BN 5
J 2
(900 3910);
DISPLAY 0.617021 (900 3910);
PAINT PINK (900 3910);
FORCEPROP 1 LAST PATH I30
J 2
(900 3900);
DISPLAY 0.936170 (900 3900);
PAINT GREEN (900 3900);
DISPLAY INVISIBLE (900 3900);
FORCEPROP 1 LAST HDL_TAP TRUE
J 2
(575 3775);
DISPLAY 1.234043 (575 3775);
PAINT GREEN (575 3775);
DISPLAY INVISIBLE (575 3775);
FORCEPROP 1 LAST BODY_TYPE PLUMBING
J 2
(900 3850);
DISPLAY 1.234043 (900 3850);
PAINT GREEN (900 3850);
DISPLAY INVISIBLE (900 3850);
FORCEPROP 2 LAST CDS_LIB mstr_standard
J 0
(900 3900);
DISPLAY 0.787234 (900 3900);
PAINT MONO (900 3900);
DISPLAY INVISIBLE (900 3900);
FORCEADD TAP..6
R 2
(900 3800);
FORCEPROP 3 LASTPIN (850 3800) SIG_NAME M_F_DQS_DN<4>
J 0
(860 3810);
DISPLAY 0.659574 (860 3810);
PAINT MONO (860 3810);
DISPLAY INVISIBLE (860 3810);
FORCEPROP 1 LASTPIN (850 3800) BN 4
J 2
(900 3810);
DISPLAY 0.617021 (900 3810);
PAINT PINK (900 3810);
FORCEPROP 1 LAST PATH I31
J 2
(900 3800);
DISPLAY 0.936170 (900 3800);
PAINT GREEN (900 3800);
DISPLAY INVISIBLE (900 3800);
FORCEPROP 1 LAST HDL_TAP TRUE
J 2
(575 3675);
DISPLAY 1.234043 (575 3675);
PAINT GREEN (575 3675);
DISPLAY INVISIBLE (575 3675);
FORCEPROP 1 LAST BODY_TYPE PLUMBING
J 2
(900 3750);
DISPLAY 1.234043 (900 3750);
PAINT GREEN (900 3750);
DISPLAY INVISIBLE (900 3750);
FORCEPROP 2 LAST CDS_LIB mstr_standard
J 0
(900 3800);
DISPLAY 0.787234 (900 3800);
PAINT MONO (900 3800);
DISPLAY INVISIBLE (900 3800);
FORCEADD TAP..6
R 2
(900 3700);
FORCEPROP 3 LASTPIN (850 3700) SIG_NAME M_F_DQS_DN<3>
J 0
(860 3710);
DISPLAY 0.659574 (860 3710);
PAINT MONO (860 3710);
DISPLAY INVISIBLE (860 3710);
FORCEPROP 1 LASTPIN (850 3700) BN 3
J 2
(900 3710);
DISPLAY 0.617021 (900 3710);
PAINT PINK (900 3710);
FORCEPROP 1 LAST PATH I32
J 2
(900 3700);
DISPLAY 0.936170 (900 3700);
PAINT GREEN (900 3700);
DISPLAY INVISIBLE (900 3700);
FORCEPROP 1 LAST HDL_TAP TRUE
J 2
(575 3575);
DISPLAY 1.234043 (575 3575);
PAINT GREEN (575 3575);
DISPLAY INVISIBLE (575 3575);
FORCEPROP 1 LAST BODY_TYPE PLUMBING
J 2
(900 3650);
DISPLAY 1.234043 (900 3650);
PAINT GREEN (900 3650);
DISPLAY INVISIBLE (900 3650);
FORCEPROP 2 LAST CDS_LIB mstr_standard
J 0
(900 3700);
DISPLAY 0.787234 (900 3700);
PAINT MONO (900 3700);
DISPLAY INVISIBLE (900 3700);
FORCEADD TAP..6
R 2
(900 3600);
FORCEPROP 3 LASTPIN (850 3600) SIG_NAME M_F_DQS_DN<2>
J 0
(860 3610);
DISPLAY 0.659574 (860 3610);
PAINT MONO (860 3610);
DISPLAY INVISIBLE (860 3610);
FORCEPROP 1 LASTPIN (850 3600) BN 2
J 2
(900 3610);
DISPLAY 0.617021 (900 3610);
PAINT PINK (900 3610);
FORCEPROP 1 LAST PATH I33
J 2
(900 3600);
DISPLAY 0.936170 (900 3600);
PAINT GREEN (900 3600);
DISPLAY INVISIBLE (900 3600);
FORCEPROP 1 LAST HDL_TAP TRUE
J 2
(575 3475);
DISPLAY 1.234043 (575 3475);
PAINT GREEN (575 3475);
DISPLAY INVISIBLE (575 3475);
FORCEPROP 1 LAST BODY_TYPE PLUMBING
J 2
(900 3550);
DISPLAY 1.234043 (900 3550);
PAINT GREEN (900 3550);
DISPLAY INVISIBLE (900 3550);
FORCEPROP 2 LAST CDS_LIB mstr_standard
J 0
(900 3600);
DISPLAY 0.787234 (900 3600);
PAINT MONO (900 3600);
DISPLAY INVISIBLE (900 3600);
FORCEADD TAP..6
R 2
(700 3950);
FORCEPROP 3 LASTPIN (650 3950) SIG_NAME M_F_DQS_DP<5>
J 0
(660 3960);
DISPLAY 0.659574 (660 3960);
PAINT MONO (660 3960);
DISPLAY INVISIBLE (660 3960);
FORCEPROP 1 LASTPIN (650 3950) BN 5
J 2
(700 3960);
DISPLAY 0.617021 (700 3960);
PAINT PINK (700 3960);
FORCEPROP 1 LAST PATH I34
J 2
(700 3950);
DISPLAY 0.936170 (700 3950);
PAINT GREEN (700 3950);
DISPLAY INVISIBLE (700 3950);
FORCEPROP 1 LAST HDL_TAP TRUE
J 2
(375 3825);
DISPLAY 1.234043 (375 3825);
PAINT GREEN (375 3825);
DISPLAY INVISIBLE (375 3825);
FORCEPROP 1 LAST BODY_TYPE PLUMBING
J 2
(700 3900);
DISPLAY 1.234043 (700 3900);
PAINT GREEN (700 3900);
DISPLAY INVISIBLE (700 3900);
FORCEPROP 2 LAST CDS_LIB mstr_standard
J 0
(700 3950);
DISPLAY 0.787234 (700 3950);
PAINT MONO (700 3950);
DISPLAY INVISIBLE (700 3950);
FORCEADD TAP..6
R 2
(700 3850);
FORCEPROP 3 LASTPIN (650 3850) SIG_NAME M_F_DQS_DP<4>
J 0
(660 3860);
DISPLAY 0.659574 (660 3860);
PAINT MONO (660 3860);
DISPLAY INVISIBLE (660 3860);
FORCEPROP 1 LASTPIN (650 3850) BN 4
J 2
(700 3860);
DISPLAY 0.617021 (700 3860);
PAINT PINK (700 3860);
FORCEPROP 1 LAST PATH I35
J 2
(700 3850);
DISPLAY 0.936170 (700 3850);
PAINT GREEN (700 3850);
DISPLAY INVISIBLE (700 3850);
FORCEPROP 1 LAST HDL_TAP TRUE
J 2
(375 3725);
DISPLAY 1.234043 (375 3725);
PAINT GREEN (375 3725);
DISPLAY INVISIBLE (375 3725);
FORCEPROP 1 LAST BODY_TYPE PLUMBING
J 2
(700 3800);
DISPLAY 1.234043 (700 3800);
PAINT GREEN (700 3800);
DISPLAY INVISIBLE (700 3800);
FORCEPROP 2 LAST CDS_LIB mstr_standard
J 0
(700 3850);
DISPLAY 0.787234 (700 3850);
PAINT MONO (700 3850);
DISPLAY INVISIBLE (700 3850);
FORCEADD TAP..6
R 2
(700 3650);
FORCEPROP 3 LASTPIN (650 3650) SIG_NAME M_F_DQS_DP<2>
J 0
(660 3660);
DISPLAY 0.659574 (660 3660);
PAINT MONO (660 3660);
DISPLAY INVISIBLE (660 3660);
FORCEPROP 1 LASTPIN (650 3650) BN 2
J 2
(700 3660);
DISPLAY 0.617021 (700 3660);
PAINT PINK (700 3660);
FORCEPROP 1 LAST PATH I36
J 2
(700 3650);
DISPLAY 0.936170 (700 3650);
PAINT GREEN (700 3650);
DISPLAY INVISIBLE (700 3650);
FORCEPROP 1 LAST HDL_TAP TRUE
J 2
(375 3525);
DISPLAY 1.234043 (375 3525);
PAINT GREEN (375 3525);
DISPLAY INVISIBLE (375 3525);
FORCEPROP 1 LAST BODY_TYPE PLUMBING
J 2
(700 3600);
DISPLAY 1.234043 (700 3600);
PAINT GREEN (700 3600);
DISPLAY INVISIBLE (700 3600);
FORCEPROP 2 LAST CDS_LIB mstr_standard
J 0
(700 3650);
DISPLAY 0.787234 (700 3650);
PAINT MONO (700 3650);
DISPLAY INVISIBLE (700 3650);
FORCEADD TAP..6
R 2
(700 3550);
FORCEPROP 3 LASTPIN (650 3550) SIG_NAME M_F_DQS_DP<1>
J 0
(660 3560);
DISPLAY 0.659574 (660 3560);
PAINT MONO (660 3560);
DISPLAY INVISIBLE (660 3560);
FORCEPROP 1 LASTPIN (650 3550) BN 1
J 2
(700 3560);
DISPLAY 0.617021 (700 3560);
PAINT PINK (700 3560);
FORCEPROP 1 LAST PATH I37
J 2
(700 3550);
DISPLAY 0.936170 (700 3550);
PAINT GREEN (700 3550);
DISPLAY INVISIBLE (700 3550);
FORCEPROP 1 LAST HDL_TAP TRUE
J 2
(375 3425);
DISPLAY 1.234043 (375 3425);
PAINT GREEN (375 3425);
DISPLAY INVISIBLE (375 3425);
FORCEPROP 1 LAST BODY_TYPE PLUMBING
J 2
(700 3500);
DISPLAY 1.234043 (700 3500);
PAINT GREEN (700 3500);
DISPLAY INVISIBLE (700 3500);
FORCEPROP 2 LAST CDS_LIB mstr_standard
J 0
(700 3550);
DISPLAY 0.787234 (700 3550);
PAINT MONO (700 3550);
DISPLAY INVISIBLE (700 3550);
FORCEADD TAP..6
R 2
(700 3750);
FORCEPROP 3 LASTPIN (650 3750) SIG_NAME M_F_DQS_DP<3>
J 0
(660 3760);
DISPLAY 0.659574 (660 3760);
PAINT MONO (660 3760);
DISPLAY INVISIBLE (660 3760);
FORCEPROP 1 LASTPIN (650 3750) BN 3
J 2
(700 3760);
DISPLAY 0.617021 (700 3760);
PAINT PINK (700 3760);
FORCEPROP 1 LAST PATH I38
J 2
(700 3750);
DISPLAY 0.936170 (700 3750);
PAINT GREEN (700 3750);
DISPLAY INVISIBLE (700 3750);
FORCEPROP 1 LAST HDL_TAP TRUE
J 2
(375 3625);
DISPLAY 1.234043 (375 3625);
PAINT GREEN (375 3625);
DISPLAY INVISIBLE (375 3625);
FORCEPROP 1 LAST BODY_TYPE PLUMBING
J 2
(700 3700);
DISPLAY 1.234043 (700 3700);
PAINT GREEN (700 3700);
DISPLAY INVISIBLE (700 3700);
FORCEPROP 2 LAST CDS_LIB mstr_standard
J 0
(700 3750);
DISPLAY 0.787234 (700 3750);
PAINT MONO (700 3750);
DISPLAY INVISIBLE (700 3750);
FORCEADD TAP..6
R 2
(900 3400);
FORCEPROP 3 LASTPIN (850 3400) SIG_NAME M_F_DQS_DN<0>
J 0
(860 3410);
DISPLAY 0.659574 (860 3410);
PAINT MONO (860 3410);
DISPLAY INVISIBLE (860 3410);
FORCEPROP 1 LASTPIN (850 3400) BN 0
J 2
(900 3410);
DISPLAY 0.617021 (900 3410);
PAINT PINK (900 3410);
FORCEPROP 1 LAST PATH I39
J 2
(900 3400);
DISPLAY 0.936170 (900 3400);
PAINT GREEN (900 3400);
DISPLAY INVISIBLE (900 3400);
FORCEPROP 1 LAST HDL_TAP TRUE
J 2
(575 3275);
DISPLAY 1.234043 (575 3275);
PAINT GREEN (575 3275);
DISPLAY INVISIBLE (575 3275);
FORCEPROP 1 LAST BODY_TYPE PLUMBING
J 2
(900 3350);
DISPLAY 1.234043 (900 3350);
PAINT GREEN (900 3350);
DISPLAY INVISIBLE (900 3350);
FORCEPROP 2 LAST CDS_LIB mstr_standard
J 0
(900 3400);
DISPLAY 0.787234 (900 3400);
PAINT MONO (900 3400);
DISPLAY INVISIBLE (900 3400);
FORCEADD TAP..6
R 2
(700 5150);
FORCEPROP 3 LASTPIN (650 5150) SIG_NAME M_F_DQS_DP<17>
J 0
(660 5160);
DISPLAY 0.659574 (660 5160);
PAINT MONO (660 5160);
DISPLAY INVISIBLE (660 5160);
FORCEPROP 1 LASTPIN (650 5150) BN 17
J 2
(700 5160);
DISPLAY 0.617021 (700 5160);
PAINT PINK (700 5160);
FORCEPROP 1 LAST PATH I4
J 2
(700 5150);
DISPLAY 0.936170 (700 5150);
PAINT GREEN (700 5150);
DISPLAY INVISIBLE (700 5150);
FORCEPROP 1 LAST HDL_TAP TRUE
J 2
(375 5025);
DISPLAY 1.234043 (375 5025);
PAINT GREEN (375 5025);
DISPLAY INVISIBLE (375 5025);
FORCEPROP 1 LAST BODY_TYPE PLUMBING
J 2
(700 5100);
DISPLAY 1.234043 (700 5100);
PAINT GREEN (700 5100);
DISPLAY INVISIBLE (700 5100);
FORCEPROP 2 LAST CDS_LIB mstr_standard
J 2
(700 5150);
DISPLAY 0.787234 (700 5150);
PAINT MONO (700 5150);
DISPLAY INVISIBLE (700 5150);
FORCEADD TAP..6
R 2
(900 3500);
FORCEPROP 3 LASTPIN (850 3500) SIG_NAME M_F_DQS_DN<1>
J 0
(860 3510);
DISPLAY 0.659574 (860 3510);
PAINT MONO (860 3510);
DISPLAY INVISIBLE (860 3510);
FORCEPROP 1 LASTPIN (850 3500) BN 1
J 2
(900 3510);
DISPLAY 0.617021 (900 3510);
PAINT PINK (900 3510);
FORCEPROP 1 LAST PATH I40
J 2
(900 3500);
DISPLAY 0.936170 (900 3500);
PAINT GREEN (900 3500);
DISPLAY INVISIBLE (900 3500);
FORCEPROP 1 LAST HDL_TAP TRUE
J 2
(575 3375);
DISPLAY 1.234043 (575 3375);
PAINT GREEN (575 3375);
DISPLAY INVISIBLE (575 3375);
FORCEPROP 1 LAST BODY_TYPE PLUMBING
J 2
(900 3450);
DISPLAY 1.234043 (900 3450);
PAINT GREEN (900 3450);
DISPLAY INVISIBLE (900 3450);
FORCEPROP 2 LAST CDS_LIB mstr_standard
J 0
(900 3500);
DISPLAY 0.787234 (900 3500);
PAINT MONO (900 3500);
DISPLAY INVISIBLE (900 3500);
FORCEADD TAP..6
R 2
(700 3450);
FORCEPROP 3 LASTPIN (650 3450) SIG_NAME M_F_DQS_DP<0>
J 0
(660 3460);
DISPLAY 0.659574 (660 3460);
PAINT MONO (660 3460);
DISPLAY INVISIBLE (660 3460);
FORCEPROP 1 LASTPIN (650 3450) BN 0
J 2
(700 3460);
DISPLAY 0.617021 (700 3460);
PAINT PINK (700 3460);
FORCEPROP 1 LAST PATH I41
J 2
(700 3450);
DISPLAY 0.936170 (700 3450);
PAINT GREEN (700 3450);
DISPLAY INVISIBLE (700 3450);
FORCEPROP 1 LAST HDL_TAP TRUE
J 2
(375 3325);
DISPLAY 1.234043 (375 3325);
PAINT GREEN (375 3325);
DISPLAY INVISIBLE (375 3325);
FORCEPROP 1 LAST BODY_TYPE PLUMBING
J 2
(700 3400);
DISPLAY 1.234043 (700 3400);
PAINT GREEN (700 3400);
DISPLAY INVISIBLE (700 3400);
FORCEPROP 2 LAST CDS_LIB mstr_standard
J 0
(700 3450);
DISPLAY 0.787234 (700 3450);
PAINT MONO (700 3450);
DISPLAY INVISIBLE (700 3450);
FORCEADD SCONN288_H44441003..3
(1800 2550);
FORCEPROP 2 LASTPIN (1300 3400) $PN 15
J 2
(1290 3410);
DISPLAY 0.617021 (1290 3410);
PAINT ORANGE (1290 3410);
FORCEPROP 2 LASTPIN (2300 2600) $PN 195
J 0
(2310 2610);
DISPLAY 0.617021 (2310 2610);
PAINT ORANGE (2310 2610);
FORCEPROP 2 LASTPIN (1300 1950) $PN 114
J 2
(1290 1960);
DISPLAY 0.617021 (1290 1960);
PAINT ORANGE (1290 1960);
FORCEPROP 1 LAST MATERIAL SCONN
J 0
(1350 3900);
DISPLAY 0.617021 (1350 3900);
PAINT SKYBLUE (1350 3900);
FORCEPROP 2 LASTPIN (2300 3700) $PN 147
J 0
(2310 3710);
DISPLAY 0.617021 (2310 3710);
PAINT ORANGE (2310 3710);
FORCEPROP 2 LASTPIN (1300 3250) $PN 22
J 2
(1290 3260);
DISPLAY 0.617021 (1290 3260);
PAINT ORANGE (1290 3260);
FORCEPROP 2 LASTPIN (1300 3200) $PN 24
J 2
(1290 3210);
DISPLAY 0.617021 (1290 3210);
PAINT ORANGE (1290 3210);
FORCEPROP 2 LASTPIN (1300 2900) $PN 37
J 2
(1290 2910);
DISPLAY 0.617021 (1290 2910);
PAINT ORANGE (1290 2910);
FORCEPROP 2 LASTPIN (1300 2850) $PN 39
J 2
(1290 2860);
DISPLAY 0.617021 (1290 2860);
PAINT ORANGE (1290 2860);
FORCEPROP 2 LASTPIN (1300 2800) $PN 42
J 2
(1290 2810);
DISPLAY 0.617021 (1290 2810);
PAINT ORANGE (1290 2810);
FORCEPROP 2 LASTPIN (1300 2750) $PN 44
J 2
(1290 2760);
DISPLAY 0.617021 (1290 2760);
PAINT ORANGE (1290 2760);
FORCEPROP 2 LASTPIN (2300 3450) $PN 158
J 0
(2310 3460);
DISPLAY 0.617021 (2310 3460);
PAINT ORANGE (2310 3460);
FORCEPROP 2 LASTPIN (2300 3600) $PN 151
J 0
(2310 3610);
DISPLAY 0.617021 (2310 3610);
PAINT ORANGE (2310 3610);
FORCEPROP 2 LASTPIN (1300 2550) $PN 53
J 2
(1290 2560);
DISPLAY 0.617021 (1290 2560);
PAINT ORANGE (1290 2560);
FORCEPROP 2 LASTPIN (2300 1400) $PN 283
J 0
(2310 1410);
DISPLAY 0.617021 (2310 1410);
PAINT ORANGE (2310 1410);
FORCEPROP 2 LASTPIN (2300 1450) $PN 281
J 0
(2310 1460);
DISPLAY 0.617021 (2310 1460);
PAINT ORANGE (2310 1460);
FORCEPROP 2 LASTPIN (2300 1500) $PN 279
J 0
(2310 1510);
DISPLAY 0.617021 (2310 1510);
PAINT ORANGE (2310 1510);
FORCEPROP 2 LASTPIN (2300 1550) $PN 276
J 0
(2310 1560);
DISPLAY 0.617021 (2310 1560);
PAINT ORANGE (2310 1560);
FORCEPROP 2 LASTPIN (2300 1600) $PN 274
J 0
(2310 1610);
DISPLAY 0.617021 (2310 1610);
PAINT ORANGE (2310 1610);
FORCEPROP 2 LASTPIN (2300 1650) $PN 272
J 0
(2310 1660);
DISPLAY 0.617021 (2310 1660);
PAINT ORANGE (2310 1660);
FORCEPROP 2 LASTPIN (2300 1700) $PN 270
J 0
(2310 1710);
DISPLAY 0.617021 (2310 1710);
PAINT ORANGE (2310 1710);
FORCEPROP 2 LASTPIN (2300 1750) $PN 268
J 0
(2310 1760);
DISPLAY 0.617021 (2310 1760);
PAINT ORANGE (2310 1760);
FORCEPROP 2 LASTPIN (2300 1800) $PN 265
J 0
(2310 1810);
DISPLAY 0.617021 (2310 1810);
PAINT ORANGE (2310 1810);
FORCEPROP 2 LASTPIN (2300 1850) $PN 263
J 0
(2310 1860);
DISPLAY 0.617021 (2310 1860);
PAINT ORANGE (2310 1860);
FORCEPROP 2 LASTPIN (2300 1900) $PN 261
J 0
(2310 1910);
DISPLAY 0.617021 (2310 1910);
PAINT ORANGE (2310 1910);
FORCEPROP 2 LASTPIN (2300 1950) $PN 259
J 0
(2310 1960);
DISPLAY 0.617021 (2310 1960);
PAINT ORANGE (2310 1960);
FORCEPROP 2 LASTPIN (2300 2000) $PN 257
J 0
(2310 2010);
DISPLAY 0.617021 (2310 2010);
PAINT ORANGE (2310 2010);
FORCEPROP 2 LASTPIN (2300 2050) $PN 254
J 0
(2310 2060);
DISPLAY 0.617021 (2310 2060);
PAINT ORANGE (2310 2060);
FORCEPROP 2 LASTPIN (2300 2100) $PN 252
J 0
(2310 2110);
DISPLAY 0.617021 (2310 2110);
PAINT ORANGE (2310 2110);
FORCEPROP 2 LASTPIN (2300 2150) $PN 250
J 0
(2310 2160);
DISPLAY 0.617021 (2310 2160);
PAINT ORANGE (2310 2160);
FORCEPROP 2 LASTPIN (2300 2200) $PN 248
J 0
(2310 2210);
DISPLAY 0.617021 (2310 2210);
PAINT ORANGE (2310 2210);
FORCEPROP 2 LASTPIN (2300 2250) $PN 246
J 0
(2310 2260);
DISPLAY 0.617021 (2310 2260);
PAINT ORANGE (2310 2260);
FORCEPROP 2 LASTPIN (2300 2300) $PN 243
J 0
(2310 2310);
DISPLAY 0.617021 (2310 2310);
PAINT ORANGE (2310 2310);
FORCEPROP 2 LASTPIN (2300 2350) $PN 241
J 0
(2310 2360);
DISPLAY 0.617021 (2310 2360);
PAINT ORANGE (2310 2360);
FORCEPROP 2 LASTPIN (2300 2400) $PN 239
J 0
(2310 2410);
DISPLAY 0.617021 (2310 2410);
PAINT ORANGE (2310 2410);
FORCEPROP 2 LASTPIN (2300 2450) $PN 202
J 0
(2310 2460);
DISPLAY 0.617021 (2310 2460);
PAINT ORANGE (2310 2460);
FORCEPROP 2 LASTPIN (2300 2500) $PN 200
J 0
(2310 2510);
DISPLAY 0.617021 (2310 2510);
PAINT ORANGE (2310 2510);
FORCEPROP 2 LASTPIN (2300 2550) $PN 198
J 0
(2310 2560);
DISPLAY 0.617021 (2310 2560);
PAINT ORANGE (2310 2560);
FORCEPROP 2 LASTPIN (2300 2650) $PN 193
J 0
(2310 2660);
DISPLAY 0.617021 (2310 2660);
PAINT ORANGE (2310 2660);
FORCEPROP 2 LASTPIN (2300 2700) $PN 191
J 0
(2310 2710);
DISPLAY 0.617021 (2310 2710);
PAINT ORANGE (2310 2710);
FORCEPROP 2 LASTPIN (2300 2750) $PN 189
J 0
(2310 2760);
DISPLAY 0.617021 (2310 2760);
PAINT ORANGE (2310 2760);
FORCEPROP 2 LASTPIN (2300 2800) $PN 187
J 0
(2310 2810);
DISPLAY 0.617021 (2310 2810);
PAINT ORANGE (2310 2810);
FORCEPROP 2 LASTPIN (2300 2850) $PN 184
J 0
(2310 2860);
DISPLAY 0.617021 (2310 2860);
PAINT ORANGE (2310 2860);
FORCEPROP 2 LASTPIN (2300 2900) $PN 182
J 0
(2310 2910);
DISPLAY 0.617021 (2310 2910);
PAINT ORANGE (2310 2910);
FORCEPROP 2 LASTPIN (2300 2950) $PN 180
J 0
(2310 2960);
DISPLAY 0.617021 (2310 2960);
PAINT ORANGE (2310 2960);
FORCEPROP 2 LASTPIN (2300 3000) $PN 178
J 0
(2310 3010);
DISPLAY 0.617021 (2310 3010);
PAINT ORANGE (2310 3010);
FORCEPROP 2 LASTPIN (2300 3050) $PN 176
J 0
(2310 3060);
DISPLAY 0.617021 (2310 3060);
PAINT ORANGE (2310 3060);
FORCEPROP 2 LASTPIN (2300 3100) $PN 173
J 0
(2310 3110);
DISPLAY 0.617021 (2310 3110);
PAINT ORANGE (2310 3110);
FORCEPROP 2 LASTPIN (2300 3150) $PN 171
J 0
(2310 3160);
DISPLAY 0.617021 (2310 3160);
PAINT ORANGE (2310 3160);
FORCEPROP 2 LASTPIN (2300 3200) $PN 169
J 0
(2310 3210);
DISPLAY 0.617021 (2310 3210);
PAINT ORANGE (2310 3210);
FORCEPROP 2 LASTPIN (2300 3250) $PN 167
J 0
(2310 3260);
DISPLAY 0.617021 (2310 3260);
PAINT ORANGE (2310 3260);
FORCEPROP 2 LASTPIN (2300 3300) $PN 165
J 0
(2310 3310);
DISPLAY 0.617021 (2310 3310);
PAINT ORANGE (2310 3310);
FORCEPROP 2 LASTPIN (2300 3350) $PN 162
J 0
(2310 3360);
DISPLAY 0.617021 (2310 3360);
PAINT ORANGE (2310 3360);
FORCEPROP 2 LASTPIN (2300 3400) $PN 160
J 0
(2310 3410);
DISPLAY 0.617021 (2310 3410);
PAINT ORANGE (2310 3410);
FORCEPROP 2 LASTPIN (2300 3500) $PN 156
J 0
(2310 3510);
DISPLAY 0.617021 (2310 3510);
PAINT ORANGE (2310 3510);
FORCEPROP 2 LASTPIN (2300 3550) $PN 154
J 0
(2310 3560);
DISPLAY 0.617021 (2310 3560);
PAINT ORANGE (2310 3560);
FORCEPROP 2 LASTPIN (2300 3650) $PN 149
J 0
(2310 3660);
DISPLAY 0.617021 (2310 3660);
PAINT ORANGE (2310 3660);
FORCEPROP 2 LASTPIN (1300 1400) $PN 138
J 2
(1290 1410);
DISPLAY 0.617021 (1290 1410);
PAINT ORANGE (1290 1410);
FORCEPROP 2 LASTPIN (1300 1450) $PN 136
J 2
(1290 1460);
DISPLAY 0.617021 (1290 1460);
PAINT ORANGE (1290 1460);
FORCEPROP 2 LASTPIN (1300 1550) $PN 131
J 2
(1290 1560);
DISPLAY 0.617021 (1290 1560);
PAINT ORANGE (1290 1560);
FORCEPROP 2 LASTPIN (1300 1600) $PN 129
J 2
(1290 1610);
DISPLAY 0.617021 (1290 1610);
PAINT ORANGE (1290 1610);
FORCEPROP 2 LASTPIN (1300 1650) $PN 127
J 2
(1290 1660);
DISPLAY 0.617021 (1290 1660);
PAINT ORANGE (1290 1660);
FORCEPROP 2 LASTPIN (1300 1700) $PN 125
J 2
(1290 1710);
DISPLAY 0.617021 (1290 1710);
PAINT ORANGE (1290 1710);
FORCEPROP 2 LASTPIN (1300 1750) $PN 123
J 2
(1290 1760);
DISPLAY 0.617021 (1290 1760);
PAINT ORANGE (1290 1760);
FORCEPROP 2 LASTPIN (1300 1800) $PN 120
J 2
(1290 1810);
DISPLAY 0.617021 (1290 1810);
PAINT ORANGE (1290 1810);
FORCEPROP 2 LASTPIN (1300 1850) $PN 118
J 2
(1290 1860);
DISPLAY 0.617021 (1290 1860);
PAINT ORANGE (1290 1860);
FORCEPROP 2 LASTPIN (1300 1900) $PN 116
J 2
(1290 1910);
DISPLAY 0.617021 (1290 1910);
PAINT ORANGE (1290 1910);
FORCEPROP 2 LASTPIN (1300 2000) $PN 112
J 2
(1290 2010);
DISPLAY 0.617021 (1290 2010);
PAINT ORANGE (1290 2010);
FORCEPROP 2 LASTPIN (1300 2050) $PN 109
J 2
(1290 2060);
DISPLAY 0.617021 (1290 2060);
PAINT ORANGE (1290 2060);
FORCEPROP 2 LASTPIN (1300 2100) $PN 107
J 2
(1290 2110);
DISPLAY 0.617021 (1290 2110);
PAINT ORANGE (1290 2110);
FORCEPROP 2 LASTPIN (1300 2150) $PN 105
J 2
(1290 2160);
DISPLAY 0.617021 (1290 2160);
PAINT ORANGE (1290 2160);
FORCEPROP 2 LASTPIN (1300 2200) $PN 103
J 2
(1290 2210);
DISPLAY 0.617021 (1290 2210);
PAINT ORANGE (1290 2210);
FORCEPROP 2 LASTPIN (1300 2250) $PN 101
J 2
(1290 2260);
DISPLAY 0.617021 (1290 2260);
PAINT ORANGE (1290 2260);
FORCEPROP 2 LASTPIN (1300 2300) $PN 98
J 2
(1290 2310);
DISPLAY 0.617021 (1290 2310);
PAINT ORANGE (1290 2310);
FORCEPROP 2 LASTPIN (1300 2350) $PN 96
J 2
(1290 2360);
DISPLAY 0.617021 (1290 2360);
PAINT ORANGE (1290 2360);
FORCEPROP 2 LASTPIN (1300 2400) $PN 94
J 2
(1290 2410);
DISPLAY 0.617021 (1290 2410);
PAINT ORANGE (1290 2410);
FORCEPROP 2 LASTPIN (1300 2450) $PN 57
J 2
(1290 2460);
DISPLAY 0.617021 (1290 2460);
PAINT ORANGE (1290 2460);
FORCEPROP 2 LASTPIN (1300 2500) $PN 55
J 2
(1290 2510);
DISPLAY 0.617021 (1290 2510);
PAINT ORANGE (1290 2510);
FORCEPROP 2 LASTPIN (1300 2600) $PN 50
J 2
(1290 2610);
DISPLAY 0.617021 (1290 2610);
PAINT ORANGE (1290 2610);
FORCEPROP 2 LASTPIN (1300 2650) $PN 48
J 2
(1290 2660);
DISPLAY 0.617021 (1290 2660);
PAINT ORANGE (1290 2660);
FORCEPROP 2 LASTPIN (1300 2700) $PN 46
J 2
(1290 2710);
DISPLAY 0.617021 (1290 2710);
PAINT ORANGE (1290 2710);
FORCEPROP 2 LASTPIN (1300 2950) $PN 35
J 2
(1290 2960);
DISPLAY 0.617021 (1290 2960);
PAINT ORANGE (1290 2960);
FORCEPROP 2 LASTPIN (1300 3000) $PN 33
J 2
(1290 3010);
DISPLAY 0.617021 (1290 3010);
PAINT ORANGE (1290 3010);
FORCEPROP 2 LASTPIN (1300 3100) $PN 28
J 2
(1290 3110);
DISPLAY 0.617021 (1290 3110);
PAINT ORANGE (1290 3110);
FORCEPROP 2 LASTPIN (1300 3150) $PN 26
J 2
(1290 3160);
DISPLAY 0.617021 (1290 3160);
PAINT ORANGE (1290 3160);
FORCEPROP 2 LASTPIN (1300 3300) $PN 20
J 2
(1290 3310);
DISPLAY 0.617021 (1290 3310);
PAINT ORANGE (1290 3310);
FORCEPROP 2 LASTPIN (1300 3350) $PN 17
J 2
(1290 3360);
DISPLAY 0.617021 (1290 3360);
PAINT ORANGE (1290 3360);
FORCEPROP 2 LASTPIN (1300 3450) $PN 13
J 2
(1290 3460);
DISPLAY 0.617021 (1290 3460);
PAINT ORANGE (1290 3460);
FORCEPROP 2 LASTPIN (1300 3500) $PN 11
J 2
(1290 3510);
DISPLAY 0.617021 (1290 3510);
PAINT ORANGE (1290 3510);
FORCEPROP 2 LASTPIN (1300 3550) $PN 9
J 2
(1290 3560);
DISPLAY 0.617021 (1290 3560);
PAINT ORANGE (1290 3560);
FORCEPROP 2 LASTPIN (1300 3600) $PN 6
J 2
(1290 3610);
DISPLAY 0.617021 (1290 3610);
PAINT ORANGE (1290 3610);
FORCEPROP 2 LASTPIN (1300 3650) $PN 4
J 2
(1290 3660);
DISPLAY 0.617021 (1290 3660);
PAINT ORANGE (1290 3660);
FORCEPROP 2 LASTPIN (1300 3700) $PN 2
J 2
(1290 3710);
DISPLAY 0.617021 (1290 3710);
PAINT ORANGE (1290 3710);
FORCEPROP 1 LAST PART_NUMBER H44441-003
J 0
(1350 1200);
DISPLAY 0.617021 (1350 1200);
PAINT BLUE (1350 1200);
FORCEPROP 1 LAST LOCATION J6L1
J 0
(1350 3950);
DISPLAY 0.617021 (1350 3950);
PAINT AQUA (1350 3950);
FORCEPROP 0 LAST BOM_SS NOPOP
J 0
(1525 3975);
DISPLAY 1.021277 (1525 3975);
PAINT BROWN (1525 3975);
DISPLAY BOTH (1525 3975);
FORCEPROP 2 LASTPIN (1300 3050) $PN 31
J 2
(1290 3060);
DISPLAY 0.617021 (1290 3060);
PAINT ORANGE (1290 3060);
FORCEPROP 2 LASTPIN (1300 1500) $PN 134
J 2
(1290 1510);
DISPLAY 0.617021 (1290 1510);
PAINT ORANGE (1290 1510);
FORCEPROP 2 LAST ROOM DDR4_CH_F1
J 0
(1800 2550);
PAINT ORANGE (1800 2550);
DISPLAY INVISIBLE (1800 2550);
FORCEPROP 1 LAST PATH I43
J 0
(1800 3900);
PAINT GREEN (1800 3900);
DISPLAY INVISIBLE (1800 3900);
FORCEPROP 2 LAST CDS_LOCATION J6L1
J 0
(1350 3950);
DISPLAY 0.617021 (1350 3950);
PAINT AQUA (1350 3950);
DISPLAY INVISIBLE (1350 3950);
FORCEPROP 2 LAST SEC 3
J 0
(1350 4000);
DISPLAY 0.680851 (1350 4000);
PAINT MONO (1350 4000);
DISPLAY INVISIBLE (1350 4000);
FORCEPROP 2 LAST SEC_TYPE PIP
J 0
(1350 4000);
DISPLAY 1.021277 (1350 4000);
PAINT ORANGE (1350 4000);
DISPLAY INVISIBLE (1350 4000);
FORCEPROP 2 LAST CDS_LIB mstr_sconn
J 0
(1800 2550);
PAINT ORANGE (1800 2550);
DISPLAY INVISIBLE (1800 2550);
FORCEPROP 2 LAST BOM_COST MEM
J 0
(1800 2550);
PAINT ORANGE (1800 2550);
DISPLAY INVISIBLE (1800 2550);
FORCEPROP 1 LAST PACK_TYPE PIP
J 0
(1350 4000);
PAINT SKYBLUE (1350 4000);
DISPLAY INVISIBLE (1350 4000);
FORCEADD GND..1
R 2
(1100 1250);
FORCEPROP 3 LASTPIN (1100 1300) SIG_NAME GND\g
J 0
(1110 1310);
DISPLAY 0.659574 (1110 1310);
PAINT MONO (1110 1310);
DISPLAY INVISIBLE (1110 1310);
FORCEPROP 1 LAST HDL_POWER GND
J 2
(1100 1400);
DISPLAY 0.553191 (1100 1400);
PAINT GREEN (1100 1400);
DISPLAY INVISIBLE (1100 1400);
FORCEPROP 2 LAST ROOM DDR4_CH_C
J 0
(1100 1255);
PAINT ORANGE (1100 1255);
DISPLAY INVISIBLE (1100 1255);
FORCEPROP 1 LAST PATH I44
J 2
(1025 1250);
DISPLAY 0.936170 (1025 1250);
PAINT GREEN (1025 1250);
DISPLAY INVISIBLE (1025 1250);
FORCEPROP 1 LAST BODY_TYPE PLUMBING
J 2
(1145 1207);
DISPLAY 0.340426 (1145 1207);
PAINT GREEN (1145 1207);
DISPLAY INVISIBLE (1145 1207);
FORCEPROP 2 LAST BOM_COST MEM
J 0
(1100 1255);
PAINT ORANGE (1100 1255);
DISPLAY INVISIBLE (1100 1255);
FORCEPROP 1 LAST SIZE 1B
J 2
(1025 1200);
DISPLAY 1.170213 (1025 1200);
PAINT GREEN (1025 1200);
DISPLAY INVISIBLE (1025 1200);
FORCEPROP 2 LAST CDS_LIB mstr_symbols
J 0
(1100 1250);
DISPLAY 0.787234 (1100 1250);
PAINT MONO (1100 1250);
DISPLAY INVISIBLE (1100 1250);
FORCEPROP 1 LAST VOLTAGE 0
J 0
(1100 1250);
PAINT SKYBLUE (1100 1250);
DISPLAY INVISIBLE (1100 1250);
FORCEADD OFFPAGE..3
(-1100 4800);
FORCEPROP 2 LAST $XR1 53 
J 0
(-796 4800);
DISPLAY 0.638298 (-796 4800);
PAINT MONO (-796 4800);
FORCEPROP 2 LAST $XR0 28 
J 0
(-886 4800);
DISPLAY 0.638298 (-886 4800);
PAINT MONO (-886 4800);
FORCEPROP 2 LAST PATH I45
J 0
(-900 4875);
DISPLAY 0.787234 (-900 4875);
PAINT MONO (-900 4875);
DISPLAY INVISIBLE (-900 4875);
FORCEPROP 1 LAST COMMENT_BODY TRUE
J 0
(-1150 4700);
DISPLAY 0.936170 (-1150 4700);
PAINT GREEN (-1150 4700);
DISPLAY INVISIBLE (-1150 4700);
FORCEPROP 1 LAST OFFPAGE TRUE
J 0
(-775 4675);
DISPLAY 0.936170 (-775 4675);
PAINT GREEN (-775 4675);
DISPLAY INVISIBLE (-775 4675);
FORCEPROP 2 LAST CDS_LIB mstr_standard
J 0
(-1100 4800);
DISPLAY 0.787234 (-1100 4800);
PAINT MONO (-1100 4800);
DISPLAY INVISIBLE (-1100 4800);
FORCEADD TAP..6
R 2
(-1650 4650);
FORCEPROP 3 LASTPIN (-1700 4650) SIG_NAME M_F_DQ<61>
J 0
(-1690 4660);
DISPLAY 0.659574 (-1690 4660);
PAINT MONO (-1690 4660);
DISPLAY INVISIBLE (-1690 4660);
FORCEPROP 1 LASTPIN (-1700 4650) BN 61
J 2
(-1650 4660);
DISPLAY 0.617021 (-1650 4660);
PAINT PINK (-1650 4660);
FORCEPROP 1 LAST PATH I46
J 2
(-1650 4650);
DISPLAY 0.936170 (-1650 4650);
PAINT GREEN (-1650 4650);
DISPLAY INVISIBLE (-1650 4650);
FORCEPROP 1 LAST HDL_TAP TRUE
J 2
(-1975 4525);
DISPLAY 1.234043 (-1975 4525);
PAINT GREEN (-1975 4525);
DISPLAY INVISIBLE (-1975 4525);
FORCEPROP 1 LAST BODY_TYPE PLUMBING
J 2
(-1650 4600);
DISPLAY 1.234043 (-1650 4600);
PAINT GREEN (-1650 4600);
DISPLAY INVISIBLE (-1650 4600);
FORCEPROP 2 LAST CDS_LIB mstr_standard
J 2
(-1650 4650);
DISPLAY 0.787234 (-1650 4650);
PAINT MONO (-1650 4650);
DISPLAY INVISIBLE (-1650 4650);
FORCEADD TAP..6
R 2
(-1650 4600);
FORCEPROP 3 LASTPIN (-1700 4600) SIG_NAME M_F_DQ<60>
J 0
(-1690 4610);
DISPLAY 0.659574 (-1690 4610);
PAINT MONO (-1690 4610);
DISPLAY INVISIBLE (-1690 4610);
FORCEPROP 1 LASTPIN (-1700 4600) BN 60
J 2
(-1650 4610);
DISPLAY 0.617021 (-1650 4610);
PAINT PINK (-1650 4610);
FORCEPROP 1 LAST PATH I47
J 2
(-1650 4600);
DISPLAY 0.936170 (-1650 4600);
PAINT GREEN (-1650 4600);
DISPLAY INVISIBLE (-1650 4600);
FORCEPROP 1 LAST HDL_TAP TRUE
J 2
(-1975 4475);
DISPLAY 1.234043 (-1975 4475);
PAINT GREEN (-1975 4475);
DISPLAY INVISIBLE (-1975 4475);
FORCEPROP 1 LAST BODY_TYPE PLUMBING
J 2
(-1650 4550);
DISPLAY 1.234043 (-1650 4550);
PAINT GREEN (-1650 4550);
DISPLAY INVISIBLE (-1650 4550);
FORCEPROP 2 LAST CDS_LIB mstr_standard
J 2
(-1650 4600);
DISPLAY 0.787234 (-1650 4600);
PAINT MONO (-1650 4600);
DISPLAY INVISIBLE (-1650 4600);
FORCEADD TAP..6
R 2
(-1650 4700);
FORCEPROP 3 LASTPIN (-1700 4700) SIG_NAME M_F_DQ<62>
J 0
(-1690 4710);
DISPLAY 0.659574 (-1690 4710);
PAINT MONO (-1690 4710);
DISPLAY INVISIBLE (-1690 4710);
FORCEPROP 1 LASTPIN (-1700 4700) BN 62
J 2
(-1650 4710);
DISPLAY 0.617021 (-1650 4710);
PAINT PINK (-1650 4710);
FORCEPROP 1 LAST PATH I48
J 2
(-1650 4700);
DISPLAY 0.936170 (-1650 4700);
PAINT GREEN (-1650 4700);
DISPLAY INVISIBLE (-1650 4700);
FORCEPROP 1 LAST HDL_TAP TRUE
J 2
(-1975 4575);
DISPLAY 1.234043 (-1975 4575);
PAINT GREEN (-1975 4575);
DISPLAY INVISIBLE (-1975 4575);
FORCEPROP 1 LAST BODY_TYPE PLUMBING
J 2
(-1650 4650);
DISPLAY 1.234043 (-1650 4650);
PAINT GREEN (-1650 4650);
DISPLAY INVISIBLE (-1650 4650);
FORCEPROP 2 LAST CDS_LIB mstr_standard
J 2
(-1650 4700);
DISPLAY 0.787234 (-1650 4700);
PAINT MONO (-1650 4700);
DISPLAY INVISIBLE (-1650 4700);
FORCEADD TAP..6
R 2
(-1650 4750);
FORCEPROP 3 LASTPIN (-1700 4750) SIG_NAME M_F_DQ<63>
J 0
(-1690 4760);
DISPLAY 0.659574 (-1690 4760);
PAINT MONO (-1690 4760);
DISPLAY INVISIBLE (-1690 4760);
FORCEPROP 1 LASTPIN (-1700 4750) BN 63
J 2
(-1650 4760);
DISPLAY 0.617021 (-1650 4760);
PAINT PINK (-1650 4760);
FORCEPROP 1 LAST PATH I49
J 2
(-1650 4750);
DISPLAY 0.936170 (-1650 4750);
PAINT GREEN (-1650 4750);
DISPLAY INVISIBLE (-1650 4750);
FORCEPROP 1 LAST HDL_TAP TRUE
J 2
(-1975 4625);
DISPLAY 1.234043 (-1975 4625);
PAINT GREEN (-1975 4625);
DISPLAY INVISIBLE (-1975 4625);
FORCEPROP 1 LAST BODY_TYPE PLUMBING
J 2
(-1650 4700);
DISPLAY 1.234043 (-1650 4700);
PAINT GREEN (-1650 4700);
DISPLAY INVISIBLE (-1650 4700);
FORCEPROP 2 LAST CDS_LIB mstr_standard
J 2
(-1650 4750);
DISPLAY 0.787234 (-1650 4750);
PAINT MONO (-1650 4750);
DISPLAY INVISIBLE (-1650 4750);
FORCEADD TAP..6
R 2
(900 5000);
FORCEPROP 3 LASTPIN (850 5000) SIG_NAME M_F_DQS_DN<16>
J 0
(860 5010);
DISPLAY 0.659574 (860 5010);
PAINT MONO (860 5010);
DISPLAY INVISIBLE (860 5010);
FORCEPROP 1 LASTPIN (850 5000) BN 16
J 2
(900 5010);
DISPLAY 0.617021 (900 5010);
PAINT PINK (900 5010);
FORCEPROP 1 LAST PATH I5
J 2
(900 5000);
DISPLAY 0.936170 (900 5000);
PAINT GREEN (900 5000);
DISPLAY INVISIBLE (900 5000);
FORCEPROP 1 LAST HDL_TAP TRUE
J 2
(575 4875);
DISPLAY 1.234043 (575 4875);
PAINT GREEN (575 4875);
DISPLAY INVISIBLE (575 4875);
FORCEPROP 1 LAST BODY_TYPE PLUMBING
J 2
(900 4950);
DISPLAY 1.234043 (900 4950);
PAINT GREEN (900 4950);
DISPLAY INVISIBLE (900 4950);
FORCEPROP 2 LAST CDS_LIB mstr_standard
J 0
(900 5000);
DISPLAY 0.787234 (900 5000);
PAINT MONO (900 5000);
DISPLAY INVISIBLE (900 5000);
FORCEADD TAP..6
R 2
(-1650 4350);
FORCEPROP 3 LASTPIN (-1700 4350) SIG_NAME M_F_DQ<55>
J 0
(-1690 4360);
DISPLAY 0.659574 (-1690 4360);
PAINT MONO (-1690 4360);
DISPLAY INVISIBLE (-1690 4360);
FORCEPROP 1 LASTPIN (-1700 4350) BN 55
J 2
(-1650 4360);
DISPLAY 0.617021 (-1650 4360);
PAINT PINK (-1650 4360);
FORCEPROP 1 LAST PATH I50
J 2
(-1650 4350);
DISPLAY 0.936170 (-1650 4350);
PAINT GREEN (-1650 4350);
DISPLAY INVISIBLE (-1650 4350);
FORCEPROP 1 LAST HDL_TAP TRUE
J 2
(-1975 4225);
DISPLAY 1.234043 (-1975 4225);
PAINT GREEN (-1975 4225);
DISPLAY INVISIBLE (-1975 4225);
FORCEPROP 1 LAST BODY_TYPE PLUMBING
J 2
(-1650 4300);
DISPLAY 1.234043 (-1650 4300);
PAINT GREEN (-1650 4300);
DISPLAY INVISIBLE (-1650 4300);
FORCEPROP 2 LAST CDS_LIB mstr_standard
J 2
(-1650 4350);
DISPLAY 0.787234 (-1650 4350);
PAINT MONO (-1650 4350);
DISPLAY INVISIBLE (-1650 4350);
FORCEADD TAP..6
R 2
(-1650 4400);
FORCEPROP 3 LASTPIN (-1700 4400) SIG_NAME M_F_DQ<56>
J 0
(-1690 4410);
DISPLAY 0.659574 (-1690 4410);
PAINT MONO (-1690 4410);
DISPLAY INVISIBLE (-1690 4410);
FORCEPROP 1 LASTPIN (-1700 4400) BN 56
J 2
(-1650 4410);
DISPLAY 0.617021 (-1650 4410);
PAINT PINK (-1650 4410);
FORCEPROP 1 LAST PATH I51
J 2
(-1650 4400);
DISPLAY 0.936170 (-1650 4400);
PAINT GREEN (-1650 4400);
DISPLAY INVISIBLE (-1650 4400);
FORCEPROP 1 LAST HDL_TAP TRUE
J 2
(-1975 4275);
DISPLAY 1.234043 (-1975 4275);
PAINT GREEN (-1975 4275);
DISPLAY INVISIBLE (-1975 4275);
FORCEPROP 1 LAST BODY_TYPE PLUMBING
J 2
(-1650 4350);
DISPLAY 1.234043 (-1650 4350);
PAINT GREEN (-1650 4350);
DISPLAY INVISIBLE (-1650 4350);
FORCEPROP 2 LAST CDS_LIB mstr_standard
J 2
(-1650 4400);
DISPLAY 0.787234 (-1650 4400);
PAINT MONO (-1650 4400);
DISPLAY INVISIBLE (-1650 4400);
FORCEADD TAP..6
R 2
(-1650 4500);
FORCEPROP 3 LASTPIN (-1700 4500) SIG_NAME M_F_DQ<58>
J 0
(-1690 4510);
DISPLAY 0.659574 (-1690 4510);
PAINT MONO (-1690 4510);
DISPLAY INVISIBLE (-1690 4510);
FORCEPROP 1 LASTPIN (-1700 4500) BN 58
J 2
(-1650 4510);
DISPLAY 0.617021 (-1650 4510);
PAINT PINK (-1650 4510);
FORCEPROP 1 LAST PATH I52
J 2
(-1650 4500);
DISPLAY 0.936170 (-1650 4500);
PAINT GREEN (-1650 4500);
DISPLAY INVISIBLE (-1650 4500);
FORCEPROP 1 LAST HDL_TAP TRUE
J 2
(-1975 4375);
DISPLAY 1.234043 (-1975 4375);
PAINT GREEN (-1975 4375);
DISPLAY INVISIBLE (-1975 4375);
FORCEPROP 1 LAST BODY_TYPE PLUMBING
J 2
(-1650 4450);
DISPLAY 1.234043 (-1650 4450);
PAINT GREEN (-1650 4450);
DISPLAY INVISIBLE (-1650 4450);
FORCEPROP 2 LAST CDS_LIB mstr_standard
J 2
(-1650 4500);
DISPLAY 0.787234 (-1650 4500);
PAINT MONO (-1650 4500);
DISPLAY INVISIBLE (-1650 4500);
FORCEADD TAP..6
R 2
(-1650 4450);
FORCEPROP 3 LASTPIN (-1700 4450) SIG_NAME M_F_DQ<57>
J 0
(-1690 4460);
DISPLAY 0.659574 (-1690 4460);
PAINT MONO (-1690 4460);
DISPLAY INVISIBLE (-1690 4460);
FORCEPROP 1 LASTPIN (-1700 4450) BN 57
J 2
(-1650 4460);
DISPLAY 0.617021 (-1650 4460);
PAINT PINK (-1650 4460);
FORCEPROP 1 LAST PATH I53
J 2
(-1650 4450);
DISPLAY 0.936170 (-1650 4450);
PAINT GREEN (-1650 4450);
DISPLAY INVISIBLE (-1650 4450);
FORCEPROP 1 LAST HDL_TAP TRUE
J 2
(-1975 4325);
DISPLAY 1.234043 (-1975 4325);
PAINT GREEN (-1975 4325);
DISPLAY INVISIBLE (-1975 4325);
FORCEPROP 1 LAST BODY_TYPE PLUMBING
J 2
(-1650 4400);
DISPLAY 1.234043 (-1650 4400);
PAINT GREEN (-1650 4400);
DISPLAY INVISIBLE (-1650 4400);
FORCEPROP 2 LAST CDS_LIB mstr_standard
J 2
(-1650 4450);
DISPLAY 0.787234 (-1650 4450);
PAINT MONO (-1650 4450);
DISPLAY INVISIBLE (-1650 4450);
FORCEADD TAP..6
R 2
(-1650 4550);
FORCEPROP 3 LASTPIN (-1700 4550) SIG_NAME M_F_DQ<59>
J 0
(-1690 4560);
DISPLAY 0.659574 (-1690 4560);
PAINT MONO (-1690 4560);
DISPLAY INVISIBLE (-1690 4560);
FORCEPROP 1 LASTPIN (-1700 4550) BN 59
J 2
(-1650 4560);
DISPLAY 0.617021 (-1650 4560);
PAINT PINK (-1650 4560);
FORCEPROP 1 LAST PATH I54
J 2
(-1650 4550);
DISPLAY 0.936170 (-1650 4550);
PAINT GREEN (-1650 4550);
DISPLAY INVISIBLE (-1650 4550);
FORCEPROP 1 LAST HDL_TAP TRUE
J 2
(-1975 4425);
DISPLAY 1.234043 (-1975 4425);
PAINT GREEN (-1975 4425);
DISPLAY INVISIBLE (-1975 4425);
FORCEPROP 1 LAST BODY_TYPE PLUMBING
J 2
(-1650 4500);
DISPLAY 1.234043 (-1650 4500);
PAINT GREEN (-1650 4500);
DISPLAY INVISIBLE (-1650 4500);
FORCEPROP 2 LAST CDS_LIB mstr_standard
J 2
(-1650 4550);
DISPLAY 0.787234 (-1650 4550);
PAINT MONO (-1650 4550);
DISPLAY INVISIBLE (-1650 4550);
FORCEADD TAP..6
R 2
(-1650 4100);
FORCEPROP 3 LASTPIN (-1700 4100) SIG_NAME M_F_DQ<50>
J 0
(-1690 4110);
DISPLAY 0.659574 (-1690 4110);
PAINT MONO (-1690 4110);
DISPLAY INVISIBLE (-1690 4110);
FORCEPROP 1 LASTPIN (-1700 4100) BN 50
J 2
(-1650 4110);
DISPLAY 0.617021 (-1650 4110);
PAINT PINK (-1650 4110);
FORCEPROP 1 LAST PATH I55
J 2
(-1650 4100);
DISPLAY 0.936170 (-1650 4100);
PAINT GREEN (-1650 4100);
DISPLAY INVISIBLE (-1650 4100);
FORCEPROP 1 LAST HDL_TAP TRUE
J 2
(-1975 3975);
DISPLAY 1.234043 (-1975 3975);
PAINT GREEN (-1975 3975);
DISPLAY INVISIBLE (-1975 3975);
FORCEPROP 1 LAST BODY_TYPE PLUMBING
J 2
(-1650 4050);
DISPLAY 1.234043 (-1650 4050);
PAINT GREEN (-1650 4050);
DISPLAY INVISIBLE (-1650 4050);
FORCEPROP 2 LAST CDS_LIB mstr_standard
J 2
(-1650 4100);
DISPLAY 0.787234 (-1650 4100);
PAINT MONO (-1650 4100);
DISPLAY INVISIBLE (-1650 4100);
FORCEADD TAP..6
R 2
(-1650 4150);
FORCEPROP 3 LASTPIN (-1700 4150) SIG_NAME M_F_DQ<51>
J 0
(-1690 4160);
DISPLAY 0.659574 (-1690 4160);
PAINT MONO (-1690 4160);
DISPLAY INVISIBLE (-1690 4160);
FORCEPROP 1 LASTPIN (-1700 4150) BN 51
J 2
(-1650 4160);
DISPLAY 0.617021 (-1650 4160);
PAINT PINK (-1650 4160);
FORCEPROP 1 LAST PATH I56
J 2
(-1650 4150);
DISPLAY 0.936170 (-1650 4150);
PAINT GREEN (-1650 4150);
DISPLAY INVISIBLE (-1650 4150);
FORCEPROP 1 LAST HDL_TAP TRUE
J 2
(-1975 4025);
DISPLAY 1.234043 (-1975 4025);
PAINT GREEN (-1975 4025);
DISPLAY INVISIBLE (-1975 4025);
FORCEPROP 1 LAST BODY_TYPE PLUMBING
J 2
(-1650 4100);
DISPLAY 1.234043 (-1650 4100);
PAINT GREEN (-1650 4100);
DISPLAY INVISIBLE (-1650 4100);
FORCEPROP 2 LAST CDS_LIB mstr_standard
J 2
(-1650 4150);
DISPLAY 0.787234 (-1650 4150);
PAINT MONO (-1650 4150);
DISPLAY INVISIBLE (-1650 4150);
FORCEADD TAP..6
R 2
(-1650 4200);
FORCEPROP 3 LASTPIN (-1700 4200) SIG_NAME M_F_DQ<52>
J 0
(-1690 4210);
DISPLAY 0.659574 (-1690 4210);
PAINT MONO (-1690 4210);
DISPLAY INVISIBLE (-1690 4210);
FORCEPROP 1 LASTPIN (-1700 4200) BN 52
J 2
(-1650 4210);
DISPLAY 0.617021 (-1650 4210);
PAINT PINK (-1650 4210);
FORCEPROP 1 LAST PATH I57
J 2
(-1650 4200);
DISPLAY 0.936170 (-1650 4200);
PAINT GREEN (-1650 4200);
DISPLAY INVISIBLE (-1650 4200);
FORCEPROP 1 LAST HDL_TAP TRUE
J 2
(-1975 4075);
DISPLAY 1.234043 (-1975 4075);
PAINT GREEN (-1975 4075);
DISPLAY INVISIBLE (-1975 4075);
FORCEPROP 1 LAST BODY_TYPE PLUMBING
J 2
(-1650 4150);
DISPLAY 1.234043 (-1650 4150);
PAINT GREEN (-1650 4150);
DISPLAY INVISIBLE (-1650 4150);
FORCEPROP 2 LAST CDS_LIB mstr_standard
J 2
(-1650 4200);
DISPLAY 0.787234 (-1650 4200);
PAINT MONO (-1650 4200);
DISPLAY INVISIBLE (-1650 4200);
FORCEADD TAP..6
R 2
(-1650 4300);
FORCEPROP 3 LASTPIN (-1700 4300) SIG_NAME M_F_DQ<54>
J 0
(-1690 4310);
DISPLAY 0.659574 (-1690 4310);
PAINT MONO (-1690 4310);
DISPLAY INVISIBLE (-1690 4310);
FORCEPROP 1 LASTPIN (-1700 4300) BN 54
J 2
(-1650 4310);
DISPLAY 0.617021 (-1650 4310);
PAINT PINK (-1650 4310);
FORCEPROP 1 LAST PATH I58
J 2
(-1650 4300);
DISPLAY 0.936170 (-1650 4300);
PAINT GREEN (-1650 4300);
DISPLAY INVISIBLE (-1650 4300);
FORCEPROP 1 LAST HDL_TAP TRUE
J 2
(-1975 4175);
DISPLAY 1.234043 (-1975 4175);
PAINT GREEN (-1975 4175);
DISPLAY INVISIBLE (-1975 4175);
FORCEPROP 1 LAST BODY_TYPE PLUMBING
J 2
(-1650 4250);
DISPLAY 1.234043 (-1650 4250);
PAINT GREEN (-1650 4250);
DISPLAY INVISIBLE (-1650 4250);
FORCEPROP 2 LAST CDS_LIB mstr_standard
J 2
(-1650 4300);
DISPLAY 0.787234 (-1650 4300);
PAINT MONO (-1650 4300);
DISPLAY INVISIBLE (-1650 4300);
FORCEADD TAP..6
R 2
(-1650 4250);
FORCEPROP 3 LASTPIN (-1700 4250) SIG_NAME M_F_DQ<53>
J 0
(-1690 4260);
DISPLAY 0.659574 (-1690 4260);
PAINT MONO (-1690 4260);
DISPLAY INVISIBLE (-1690 4260);
FORCEPROP 1 LASTPIN (-1700 4250) BN 53
J 2
(-1650 4260);
DISPLAY 0.617021 (-1650 4260);
PAINT PINK (-1650 4260);
FORCEPROP 1 LAST PATH I59
J 2
(-1650 4250);
DISPLAY 0.936170 (-1650 4250);
PAINT GREEN (-1650 4250);
DISPLAY INVISIBLE (-1650 4250);
FORCEPROP 1 LAST HDL_TAP TRUE
J 2
(-1975 4125);
DISPLAY 1.234043 (-1975 4125);
PAINT GREEN (-1975 4125);
DISPLAY INVISIBLE (-1975 4125);
FORCEPROP 1 LAST BODY_TYPE PLUMBING
J 2
(-1650 4200);
DISPLAY 1.234043 (-1650 4200);
PAINT GREEN (-1650 4200);
DISPLAY INVISIBLE (-1650 4200);
FORCEPROP 2 LAST CDS_LIB mstr_standard
J 2
(-1650 4250);
DISPLAY 0.787234 (-1650 4250);
PAINT MONO (-1650 4250);
DISPLAY INVISIBLE (-1650 4250);
FORCEADD TAP..6
R 2
(900 4900);
FORCEPROP 3 LASTPIN (850 4900) SIG_NAME M_F_DQS_DN<15>
J 0
(860 4910);
DISPLAY 0.659574 (860 4910);
PAINT MONO (860 4910);
DISPLAY INVISIBLE (860 4910);
FORCEPROP 1 LASTPIN (850 4900) BN 15
J 2
(900 4910);
DISPLAY 0.617021 (900 4910);
PAINT PINK (900 4910);
FORCEPROP 1 LAST PATH I6
J 2
(900 4900);
DISPLAY 0.936170 (900 4900);
PAINT GREEN (900 4900);
DISPLAY INVISIBLE (900 4900);
FORCEPROP 1 LAST HDL_TAP TRUE
J 2
(575 4775);
DISPLAY 1.234043 (575 4775);
PAINT GREEN (575 4775);
DISPLAY INVISIBLE (575 4775);
FORCEPROP 1 LAST BODY_TYPE PLUMBING
J 2
(900 4850);
DISPLAY 1.234043 (900 4850);
PAINT GREEN (900 4850);
DISPLAY INVISIBLE (900 4850);
FORCEPROP 2 LAST CDS_LIB mstr_standard
J 0
(900 4900);
DISPLAY 0.787234 (900 4900);
PAINT MONO (900 4900);
DISPLAY INVISIBLE (900 4900);
FORCEADD TAP..6
R 2
(-1650 3800);
FORCEPROP 3 LASTPIN (-1700 3800) SIG_NAME M_F_DQ<44>
J 0
(-1690 3810);
DISPLAY 0.659574 (-1690 3810);
PAINT MONO (-1690 3810);
DISPLAY INVISIBLE (-1690 3810);
FORCEPROP 1 LASTPIN (-1700 3800) BN 44
J 2
(-1650 3810);
DISPLAY 0.617021 (-1650 3810);
PAINT PINK (-1650 3810);
FORCEPROP 1 LAST PATH I60
J 2
(-1650 3800);
DISPLAY 0.936170 (-1650 3800);
PAINT GREEN (-1650 3800);
DISPLAY INVISIBLE (-1650 3800);
FORCEPROP 1 LAST HDL_TAP TRUE
J 2
(-1975 3675);
DISPLAY 1.234043 (-1975 3675);
PAINT GREEN (-1975 3675);
DISPLAY INVISIBLE (-1975 3675);
FORCEPROP 1 LAST BODY_TYPE PLUMBING
J 2
(-1650 3750);
DISPLAY 1.234043 (-1650 3750);
PAINT GREEN (-1650 3750);
DISPLAY INVISIBLE (-1650 3750);
FORCEPROP 2 LAST CDS_LIB mstr_standard
J 2
(-1650 3800);
DISPLAY 0.787234 (-1650 3800);
PAINT MONO (-1650 3800);
DISPLAY INVISIBLE (-1650 3800);
FORCEADD TAP..6
R 2
(-1650 3850);
FORCEPROP 3 LASTPIN (-1700 3850) SIG_NAME M_F_DQ<45>
J 0
(-1690 3860);
DISPLAY 0.659574 (-1690 3860);
PAINT MONO (-1690 3860);
DISPLAY INVISIBLE (-1690 3860);
FORCEPROP 1 LASTPIN (-1700 3850) BN 45
J 2
(-1650 3860);
DISPLAY 0.617021 (-1650 3860);
PAINT PINK (-1650 3860);
FORCEPROP 1 LAST PATH I61
J 2
(-1650 3850);
DISPLAY 0.936170 (-1650 3850);
PAINT GREEN (-1650 3850);
DISPLAY INVISIBLE (-1650 3850);
FORCEPROP 1 LAST HDL_TAP TRUE
J 2
(-1975 3725);
DISPLAY 1.234043 (-1975 3725);
PAINT GREEN (-1975 3725);
DISPLAY INVISIBLE (-1975 3725);
FORCEPROP 1 LAST BODY_TYPE PLUMBING
J 2
(-1650 3800);
DISPLAY 1.234043 (-1650 3800);
PAINT GREEN (-1650 3800);
DISPLAY INVISIBLE (-1650 3800);
FORCEPROP 2 LAST CDS_LIB mstr_standard
J 2
(-1650 3850);
DISPLAY 0.787234 (-1650 3850);
PAINT MONO (-1650 3850);
DISPLAY INVISIBLE (-1650 3850);
FORCEADD TAP..6
R 2
(-1650 3900);
FORCEPROP 3 LASTPIN (-1700 3900) SIG_NAME M_F_DQ<46>
J 0
(-1690 3910);
DISPLAY 0.659574 (-1690 3910);
PAINT MONO (-1690 3910);
DISPLAY INVISIBLE (-1690 3910);
FORCEPROP 1 LASTPIN (-1700 3900) BN 46
J 2
(-1650 3910);
DISPLAY 0.617021 (-1650 3910);
PAINT PINK (-1650 3910);
FORCEPROP 1 LAST PATH I62
J 2
(-1650 3900);
DISPLAY 0.936170 (-1650 3900);
PAINT GREEN (-1650 3900);
DISPLAY INVISIBLE (-1650 3900);
FORCEPROP 1 LAST HDL_TAP TRUE
J 2
(-1975 3775);
DISPLAY 1.234043 (-1975 3775);
PAINT GREEN (-1975 3775);
DISPLAY INVISIBLE (-1975 3775);
FORCEPROP 1 LAST BODY_TYPE PLUMBING
J 2
(-1650 3850);
DISPLAY 1.234043 (-1650 3850);
PAINT GREEN (-1650 3850);
DISPLAY INVISIBLE (-1650 3850);
FORCEPROP 2 LAST CDS_LIB mstr_standard
J 2
(-1650 3900);
DISPLAY 0.787234 (-1650 3900);
PAINT MONO (-1650 3900);
DISPLAY INVISIBLE (-1650 3900);
FORCEADD TAP..6
R 2
(-1650 4000);
FORCEPROP 3 LASTPIN (-1700 4000) SIG_NAME M_F_DQ<48>
J 0
(-1690 4010);
DISPLAY 0.659574 (-1690 4010);
PAINT MONO (-1690 4010);
DISPLAY INVISIBLE (-1690 4010);
FORCEPROP 1 LASTPIN (-1700 4000) BN 48
J 2
(-1650 4010);
DISPLAY 0.617021 (-1650 4010);
PAINT PINK (-1650 4010);
FORCEPROP 1 LAST PATH I63
J 2
(-1650 4000);
DISPLAY 0.936170 (-1650 4000);
PAINT GREEN (-1650 4000);
DISPLAY INVISIBLE (-1650 4000);
FORCEPROP 1 LAST HDL_TAP TRUE
J 2
(-1975 3875);
DISPLAY 1.234043 (-1975 3875);
PAINT GREEN (-1975 3875);
DISPLAY INVISIBLE (-1975 3875);
FORCEPROP 1 LAST BODY_TYPE PLUMBING
J 2
(-1650 3950);
DISPLAY 1.234043 (-1650 3950);
PAINT GREEN (-1650 3950);
DISPLAY INVISIBLE (-1650 3950);
FORCEPROP 2 LAST CDS_LIB mstr_standard
J 2
(-1650 4000);
DISPLAY 0.787234 (-1650 4000);
PAINT MONO (-1650 4000);
DISPLAY INVISIBLE (-1650 4000);
FORCEADD TAP..6
R 2
(-1650 3950);
FORCEPROP 3 LASTPIN (-1700 3950) SIG_NAME M_F_DQ<47>
J 0
(-1690 3960);
DISPLAY 0.659574 (-1690 3960);
PAINT MONO (-1690 3960);
DISPLAY INVISIBLE (-1690 3960);
FORCEPROP 1 LASTPIN (-1700 3950) BN 47
J 2
(-1650 3960);
DISPLAY 0.617021 (-1650 3960);
PAINT PINK (-1650 3960);
FORCEPROP 1 LAST PATH I64
J 2
(-1650 3950);
DISPLAY 0.936170 (-1650 3950);
PAINT GREEN (-1650 3950);
DISPLAY INVISIBLE (-1650 3950);
FORCEPROP 1 LAST HDL_TAP TRUE
J 2
(-1975 3825);
DISPLAY 1.234043 (-1975 3825);
PAINT GREEN (-1975 3825);
DISPLAY INVISIBLE (-1975 3825);
FORCEPROP 1 LAST BODY_TYPE PLUMBING
J 2
(-1650 3900);
DISPLAY 1.234043 (-1650 3900);
PAINT GREEN (-1650 3900);
DISPLAY INVISIBLE (-1650 3900);
FORCEPROP 2 LAST CDS_LIB mstr_standard
J 2
(-1650 3950);
DISPLAY 0.787234 (-1650 3950);
PAINT MONO (-1650 3950);
DISPLAY INVISIBLE (-1650 3950);
FORCEADD TAP..6
R 2
(-1650 4050);
FORCEPROP 3 LASTPIN (-1700 4050) SIG_NAME M_F_DQ<49>
J 0
(-1690 4060);
DISPLAY 0.659574 (-1690 4060);
PAINT MONO (-1690 4060);
DISPLAY INVISIBLE (-1690 4060);
FORCEPROP 1 LASTPIN (-1700 4050) BN 49
J 2
(-1650 4060);
DISPLAY 0.617021 (-1650 4060);
PAINT PINK (-1650 4060);
FORCEPROP 1 LAST PATH I65
J 2
(-1650 4050);
DISPLAY 0.936170 (-1650 4050);
PAINT GREEN (-1650 4050);
DISPLAY INVISIBLE (-1650 4050);
FORCEPROP 1 LAST HDL_TAP TRUE
J 2
(-1975 3925);
DISPLAY 1.234043 (-1975 3925);
PAINT GREEN (-1975 3925);
DISPLAY INVISIBLE (-1975 3925);
FORCEPROP 1 LAST BODY_TYPE PLUMBING
J 2
(-1650 4000);
DISPLAY 1.234043 (-1650 4000);
PAINT GREEN (-1650 4000);
DISPLAY INVISIBLE (-1650 4000);
FORCEPROP 2 LAST CDS_LIB mstr_standard
J 2
(-1650 4050);
DISPLAY 0.787234 (-1650 4050);
PAINT MONO (-1650 4050);
DISPLAY INVISIBLE (-1650 4050);
FORCEADD SCONN288_H44441003..2
(0 4300);
FORCEPROP 2 LASTPIN (450 3800) $PN 244
J 0
(460 3810);
DISPLAY 0.617021 (460 3810);
PAINT ORANGE (460 3810);
FORCEPROP 2 LASTPIN (450 3750) $PN 186
J 0
(460 3760);
DISPLAY 0.617021 (460 3760);
PAINT ORANGE (460 3760);
FORCEPROP 2 LASTPIN (450 3700) $PN 185
J 0
(460 3710);
DISPLAY 0.617021 (460 3710);
PAINT ORANGE (460 3710);
FORCEPROP 2 LASTPIN (450 3850) $PN 245
J 0
(460 3860);
DISPLAY 0.617021 (460 3860);
PAINT ORANGE (460 3860);
FORCEPROP 2 LASTPIN (450 3500) $PN 163
J 0
(460 3510);
DISPLAY 0.617021 (460 3510);
PAINT ORANGE (460 3510);
FORCEPROP 1 LAST LOCATION J6L1
J 0
(-400 5400);
DISPLAY 0.617021 (-400 5400);
PAINT AQUA (-400 5400);
FORCEPROP 2 LASTPIN (450 5150) $PN 51
J 0
(460 5160);
DISPLAY 0.617021 (460 5160);
PAINT ORANGE (460 5160);
FORCEPROP 2 LASTPIN (450 3400) $PN 152
J 0
(460 3410);
DISPLAY 0.617021 (460 3410);
PAINT ORANGE (460 3410);
FORCEPROP 2 LASTPIN (450 3450) $PN 153
J 0
(460 3460);
DISPLAY 0.617021 (460 3460);
PAINT ORANGE (460 3460);
FORCEPROP 2 LASTPIN (450 3550) $PN 164
J 0
(460 3560);
DISPLAY 0.617021 (460 3560);
PAINT ORANGE (460 3560);
FORCEPROP 2 LASTPIN (450 3600) $PN 174
J 0
(460 3610);
DISPLAY 0.617021 (460 3610);
PAINT ORANGE (460 3610);
FORCEPROP 2 LASTPIN (450 3650) $PN 175
J 0
(460 3660);
DISPLAY 0.617021 (460 3660);
PAINT ORANGE (460 3660);
FORCEPROP 2 LASTPIN (450 3900) $PN 255
J 0
(460 3910);
DISPLAY 0.617021 (460 3910);
PAINT ORANGE (460 3910);
FORCEPROP 2 LASTPIN (450 3950) $PN 256
J 0
(460 3960);
DISPLAY 0.617021 (460 3960);
PAINT ORANGE (460 3960);
FORCEPROP 2 LASTPIN (450 4000) $PN 266
J 0
(460 4010);
DISPLAY 0.617021 (460 4010);
PAINT ORANGE (460 4010);
FORCEPROP 2 LASTPIN (450 4050) $PN 267
J 0
(460 4060);
DISPLAY 0.617021 (460 4060);
PAINT ORANGE (460 4060);
FORCEPROP 2 LASTPIN (450 4100) $PN 277
J 0
(460 4110);
DISPLAY 0.617021 (460 4110);
PAINT ORANGE (460 4110);
FORCEPROP 2 LASTPIN (450 4150) $PN 278
J 0
(460 4160);
DISPLAY 0.617021 (460 4160);
PAINT ORANGE (460 4160);
FORCEPROP 2 LASTPIN (450 4200) $PN 196
J 0
(460 4210);
DISPLAY 0.617021 (460 4210);
PAINT ORANGE (460 4210);
FORCEPROP 2 LASTPIN (450 4250) $PN 197
J 0
(460 4260);
DISPLAY 0.617021 (460 4260);
PAINT ORANGE (460 4260);
FORCEPROP 2 LASTPIN (450 4300) $PN 8
J 0
(460 4310);
DISPLAY 0.617021 (460 4310);
PAINT ORANGE (460 4310);
FORCEPROP 2 LASTPIN (450 4350) $PN 7
J 0
(460 4360);
DISPLAY 0.617021 (460 4360);
PAINT ORANGE (460 4360);
FORCEPROP 2 LASTPIN (450 4400) $PN 19
J 0
(460 4410);
DISPLAY 0.617021 (460 4410);
PAINT ORANGE (460 4410);
FORCEPROP 2 LASTPIN (450 4450) $PN 18
J 0
(460 4460);
DISPLAY 0.617021 (460 4460);
PAINT ORANGE (460 4460);
FORCEPROP 2 LASTPIN (450 4500) $PN 30
J 0
(460 4510);
DISPLAY 0.617021 (460 4510);
PAINT ORANGE (460 4510);
FORCEPROP 2 LASTPIN (450 4550) $PN 29
J 0
(460 4560);
DISPLAY 0.617021 (460 4560);
PAINT ORANGE (460 4560);
FORCEPROP 2 LASTPIN (450 4600) $PN 41
J 0
(460 4610);
DISPLAY 0.617021 (460 4610);
PAINT ORANGE (460 4610);
FORCEPROP 2 LASTPIN (450 4650) $PN 40
J 0
(460 4660);
DISPLAY 0.617021 (460 4660);
PAINT ORANGE (460 4660);
FORCEPROP 2 LASTPIN (450 4700) $PN 100
J 0
(460 4710);
DISPLAY 0.617021 (460 4710);
PAINT ORANGE (460 4710);
FORCEPROP 2 LASTPIN (450 4750) $PN 99
J 0
(460 4760);
DISPLAY 0.617021 (460 4760);
PAINT ORANGE (460 4760);
FORCEPROP 2 LASTPIN (450 4800) $PN 111
J 0
(460 4810);
DISPLAY 0.617021 (460 4810);
PAINT ORANGE (460 4810);
FORCEPROP 2 LASTPIN (450 4850) $PN 110
J 0
(460 4860);
DISPLAY 0.617021 (460 4860);
PAINT ORANGE (460 4860);
FORCEPROP 2 LASTPIN (450 4900) $PN 122
J 0
(460 4910);
DISPLAY 0.617021 (460 4910);
PAINT ORANGE (460 4910);
FORCEPROP 2 LASTPIN (450 4950) $PN 121
J 0
(460 4960);
DISPLAY 0.617021 (460 4960);
PAINT ORANGE (460 4960);
FORCEPROP 2 LASTPIN (450 5000) $PN 133
J 0
(460 5010);
DISPLAY 0.617021 (460 5010);
PAINT ORANGE (460 5010);
FORCEPROP 2 LASTPIN (450 5050) $PN 132
J 0
(460 5060);
DISPLAY 0.617021 (460 5060);
PAINT ORANGE (460 5060);
FORCEPROP 2 LASTPIN (450 5100) $PN 52
J 0
(460 5110);
DISPLAY 0.617021 (460 5110);
PAINT ORANGE (460 5110);
FORCEPROP 1 LAST PART_NUMBER H44441-003
J 0
(-400 3200);
DISPLAY 0.617021 (-400 3200);
PAINT BLUE (-400 3200);
FORCEPROP 1 LAST MATERIAL SCONN
J 0
(-400 5350);
DISPLAY 0.617021 (-400 5350);
PAINT SKYBLUE (-400 5350);
FORCEPROP 0 LAST BOM_SS NOPOP
J 0
(-250 5375);
DISPLAY 1.021277 (-250 5375);
PAINT BROWN (-250 5375);
DISPLAY BOTH (-250 5375);
FORCEPROP 2 LAST ROOM DDR4_CH_F1
J 0
(-400 5500);
PAINT ORANGE (-400 5500);
DISPLAY INVISIBLE (-400 5500);
FORCEPROP 1 LAST PATH I66
J 0
(0 5350);
PAINT GREEN (0 5350);
DISPLAY INVISIBLE (0 5350);
FORCEPROP 2 LAST CDS_LOCATION J6L1
J 0
(-400 5400);
DISPLAY 0.617021 (-400 5400);
PAINT AQUA (-400 5400);
DISPLAY INVISIBLE (-400 5400);
FORCEPROP 2 LAST SEC 2
J 0
(-400 5450);
DISPLAY 0.680851 (-400 5450);
PAINT MONO (-400 5450);
DISPLAY INVISIBLE (-400 5450);
FORCEPROP 2 LAST SEC_TYPE PIP
J 0
(-400 5450);
DISPLAY 1.021277 (-400 5450);
PAINT ORANGE (-400 5450);
DISPLAY INVISIBLE (-400 5450);
FORCEPROP 2 LAST CDS_LIB mstr_sconn
J 0
(0 4300);
PAINT ORANGE (0 4300);
DISPLAY INVISIBLE (0 4300);
FORCEPROP 2 LAST BOM_COST MEM
J 0
(0 4300);
PAINT ORANGE (0 4300);
DISPLAY INVISIBLE (0 4300);
FORCEPROP 1 LAST PACK_TYPE PIP
J 0
(-400 5450);
PAINT SKYBLUE (-400 5450);
DISPLAY INVISIBLE (-400 5450);
FORCEADD TAP..6
R 2
(-1650 3650);
FORCEPROP 3 LASTPIN (-1700 3650) SIG_NAME M_F_DQ<41>
J 0
(-1690 3660);
DISPLAY 0.659574 (-1690 3660);
PAINT MONO (-1690 3660);
DISPLAY INVISIBLE (-1690 3660);
FORCEPROP 1 LASTPIN (-1700 3650) BN 41
J 2
(-1650 3660);
DISPLAY 0.617021 (-1650 3660);
PAINT PINK (-1650 3660);
FORCEPROP 1 LAST PATH I67
J 2
(-1650 3650);
DISPLAY 0.936170 (-1650 3650);
PAINT GREEN (-1650 3650);
DISPLAY INVISIBLE (-1650 3650);
FORCEPROP 1 LAST HDL_TAP TRUE
J 2
(-1975 3525);
DISPLAY 1.234043 (-1975 3525);
PAINT GREEN (-1975 3525);
DISPLAY INVISIBLE (-1975 3525);
FORCEPROP 1 LAST BODY_TYPE PLUMBING
J 2
(-1650 3600);
DISPLAY 1.234043 (-1650 3600);
PAINT GREEN (-1650 3600);
DISPLAY INVISIBLE (-1650 3600);
FORCEPROP 2 LAST CDS_LIB mstr_standard
J 2
(-1650 3650);
DISPLAY 0.787234 (-1650 3650);
PAINT MONO (-1650 3650);
DISPLAY INVISIBLE (-1650 3650);
FORCEADD TAP..6
R 2
(-1650 3550);
FORCEPROP 3 LASTPIN (-1700 3550) SIG_NAME M_F_DQ<39>
J 0
(-1690 3560);
DISPLAY 0.659574 (-1690 3560);
PAINT MONO (-1690 3560);
DISPLAY INVISIBLE (-1690 3560);
FORCEPROP 1 LASTPIN (-1700 3550) BN 39
J 2
(-1650 3560);
DISPLAY 0.617021 (-1650 3560);
PAINT PINK (-1650 3560);
FORCEPROP 1 LAST PATH I68
J 2
(-1650 3550);
DISPLAY 0.936170 (-1650 3550);
PAINT GREEN (-1650 3550);
DISPLAY INVISIBLE (-1650 3550);
FORCEPROP 1 LAST HDL_TAP TRUE
J 2
(-1975 3425);
DISPLAY 1.234043 (-1975 3425);
PAINT GREEN (-1975 3425);
DISPLAY INVISIBLE (-1975 3425);
FORCEPROP 1 LAST BODY_TYPE PLUMBING
J 2
(-1650 3500);
DISPLAY 1.234043 (-1650 3500);
PAINT GREEN (-1650 3500);
DISPLAY INVISIBLE (-1650 3500);
FORCEPROP 2 LAST CDS_LIB mstr_standard
J 2
(-1650 3550);
DISPLAY 0.787234 (-1650 3550);
PAINT MONO (-1650 3550);
DISPLAY INVISIBLE (-1650 3550);
FORCEADD TAP..6
R 2
(-1650 3600);
FORCEPROP 3 LASTPIN (-1700 3600) SIG_NAME M_F_DQ<40>
J 0
(-1690 3610);
DISPLAY 0.659574 (-1690 3610);
PAINT MONO (-1690 3610);
DISPLAY INVISIBLE (-1690 3610);
FORCEPROP 1 LASTPIN (-1700 3600) BN 40
J 2
(-1650 3610);
DISPLAY 0.617021 (-1650 3610);
PAINT PINK (-1650 3610);
FORCEPROP 1 LAST PATH I69
J 2
(-1650 3600);
DISPLAY 0.936170 (-1650 3600);
PAINT GREEN (-1650 3600);
DISPLAY INVISIBLE (-1650 3600);
FORCEPROP 1 LAST HDL_TAP TRUE
J 2
(-1975 3475);
DISPLAY 1.234043 (-1975 3475);
PAINT GREEN (-1975 3475);
DISPLAY INVISIBLE (-1975 3475);
FORCEPROP 1 LAST BODY_TYPE PLUMBING
J 2
(-1650 3550);
DISPLAY 1.234043 (-1650 3550);
PAINT GREEN (-1650 3550);
DISPLAY INVISIBLE (-1650 3550);
FORCEPROP 2 LAST CDS_LIB mstr_standard
J 2
(-1650 3600);
DISPLAY 0.787234 (-1650 3600);
PAINT MONO (-1650 3600);
DISPLAY INVISIBLE (-1650 3600);
FORCEADD TAP..6
R 2
(900 4800);
FORCEPROP 3 LASTPIN (850 4800) SIG_NAME M_F_DQS_DN<14>
J 0
(860 4810);
DISPLAY 0.659574 (860 4810);
PAINT MONO (860 4810);
DISPLAY INVISIBLE (860 4810);
FORCEPROP 1 LASTPIN (850 4800) BN 14
J 2
(900 4810);
DISPLAY 0.617021 (900 4810);
PAINT PINK (900 4810);
FORCEPROP 1 LAST PATH I7
J 2
(900 4800);
DISPLAY 0.936170 (900 4800);
PAINT GREEN (900 4800);
DISPLAY INVISIBLE (900 4800);
FORCEPROP 1 LAST HDL_TAP TRUE
J 2
(575 4675);
DISPLAY 1.234043 (575 4675);
PAINT GREEN (575 4675);
DISPLAY INVISIBLE (575 4675);
FORCEPROP 1 LAST BODY_TYPE PLUMBING
J 2
(900 4750);
DISPLAY 1.234043 (900 4750);
PAINT GREEN (900 4750);
DISPLAY INVISIBLE (900 4750);
FORCEPROP 2 LAST CDS_LIB mstr_standard
J 0
(900 4800);
DISPLAY 0.787234 (900 4800);
PAINT MONO (900 4800);
DISPLAY INVISIBLE (900 4800);
FORCEADD TAP..6
R 2
(-1650 3700);
FORCEPROP 3 LASTPIN (-1700 3700) SIG_NAME M_F_DQ<42>
J 0
(-1690 3710);
DISPLAY 0.659574 (-1690 3710);
PAINT MONO (-1690 3710);
DISPLAY INVISIBLE (-1690 3710);
FORCEPROP 1 LASTPIN (-1700 3700) BN 42
J 2
(-1650 3710);
DISPLAY 0.617021 (-1650 3710);
PAINT PINK (-1650 3710);
FORCEPROP 1 LAST PATH I70
J 2
(-1650 3700);
DISPLAY 0.936170 (-1650 3700);
PAINT GREEN (-1650 3700);
DISPLAY INVISIBLE (-1650 3700);
FORCEPROP 1 LAST HDL_TAP TRUE
J 2
(-1975 3575);
DISPLAY 1.234043 (-1975 3575);
PAINT GREEN (-1975 3575);
DISPLAY INVISIBLE (-1975 3575);
FORCEPROP 1 LAST BODY_TYPE PLUMBING
J 2
(-1650 3650);
DISPLAY 1.234043 (-1650 3650);
PAINT GREEN (-1650 3650);
DISPLAY INVISIBLE (-1650 3650);
FORCEPROP 2 LAST CDS_LIB mstr_standard
J 2
(-1650 3700);
DISPLAY 0.787234 (-1650 3700);
PAINT MONO (-1650 3700);
DISPLAY INVISIBLE (-1650 3700);
FORCEADD TAP..6
R 2
(-1650 3750);
FORCEPROP 3 LASTPIN (-1700 3750) SIG_NAME M_F_DQ<43>
J 0
(-1690 3760);
DISPLAY 0.659574 (-1690 3760);
PAINT MONO (-1690 3760);
DISPLAY INVISIBLE (-1690 3760);
FORCEPROP 1 LASTPIN (-1700 3750) BN 43
J 2
(-1650 3760);
DISPLAY 0.617021 (-1650 3760);
PAINT PINK (-1650 3760);
FORCEPROP 1 LAST PATH I71
J 2
(-1650 3750);
DISPLAY 0.936170 (-1650 3750);
PAINT GREEN (-1650 3750);
DISPLAY INVISIBLE (-1650 3750);
FORCEPROP 1 LAST HDL_TAP TRUE
J 2
(-1975 3625);
DISPLAY 1.234043 (-1975 3625);
PAINT GREEN (-1975 3625);
DISPLAY INVISIBLE (-1975 3625);
FORCEPROP 1 LAST BODY_TYPE PLUMBING
J 2
(-1650 3700);
DISPLAY 1.234043 (-1650 3700);
PAINT GREEN (-1650 3700);
DISPLAY INVISIBLE (-1650 3700);
FORCEPROP 2 LAST CDS_LIB mstr_standard
J 2
(-1650 3750);
DISPLAY 0.787234 (-1650 3750);
PAINT MONO (-1650 3750);
DISPLAY INVISIBLE (-1650 3750);
FORCEADD TAP..6
R 2
(-1650 3350);
FORCEPROP 3 LASTPIN (-1700 3350) SIG_NAME M_F_DQ<35>
J 0
(-1690 3360);
DISPLAY 0.659574 (-1690 3360);
PAINT MONO (-1690 3360);
DISPLAY INVISIBLE (-1690 3360);
FORCEPROP 1 LASTPIN (-1700 3350) BN 35
J 2
(-1650 3360);
DISPLAY 0.617021 (-1650 3360);
PAINT PINK (-1650 3360);
FORCEPROP 1 LAST PATH I72
J 2
(-1650 3350);
DISPLAY 0.936170 (-1650 3350);
PAINT GREEN (-1650 3350);
DISPLAY INVISIBLE (-1650 3350);
FORCEPROP 1 LAST HDL_TAP TRUE
J 2
(-1975 3225);
DISPLAY 1.234043 (-1975 3225);
PAINT GREEN (-1975 3225);
DISPLAY INVISIBLE (-1975 3225);
FORCEPROP 1 LAST BODY_TYPE PLUMBING
J 2
(-1650 3300);
DISPLAY 1.234043 (-1650 3300);
PAINT GREEN (-1650 3300);
DISPLAY INVISIBLE (-1650 3300);
FORCEPROP 2 LAST CDS_LIB mstr_standard
J 2
(-1650 3350);
DISPLAY 0.787234 (-1650 3350);
PAINT MONO (-1650 3350);
DISPLAY INVISIBLE (-1650 3350);
FORCEADD TAP..6
R 2
(-1650 3300);
FORCEPROP 3 LASTPIN (-1700 3300) SIG_NAME M_F_DQ<34>
J 0
(-1690 3310);
DISPLAY 0.659574 (-1690 3310);
PAINT MONO (-1690 3310);
DISPLAY INVISIBLE (-1690 3310);
FORCEPROP 1 LASTPIN (-1700 3300) BN 34
J 2
(-1650 3310);
DISPLAY 0.617021 (-1650 3310);
PAINT PINK (-1650 3310);
FORCEPROP 1 LAST PATH I73
J 2
(-1650 3300);
DISPLAY 0.936170 (-1650 3300);
PAINT GREEN (-1650 3300);
DISPLAY INVISIBLE (-1650 3300);
FORCEPROP 1 LAST HDL_TAP TRUE
J 2
(-1975 3175);
DISPLAY 1.234043 (-1975 3175);
PAINT GREEN (-1975 3175);
DISPLAY INVISIBLE (-1975 3175);
FORCEPROP 1 LAST BODY_TYPE PLUMBING
J 2
(-1650 3250);
DISPLAY 1.234043 (-1650 3250);
PAINT GREEN (-1650 3250);
DISPLAY INVISIBLE (-1650 3250);
FORCEPROP 2 LAST CDS_LIB mstr_standard
J 2
(-1650 3300);
DISPLAY 0.787234 (-1650 3300);
PAINT MONO (-1650 3300);
DISPLAY INVISIBLE (-1650 3300);
FORCEADD TAP..6
R 2
(-1650 3400);
FORCEPROP 3 LASTPIN (-1700 3400) SIG_NAME M_F_DQ<36>
J 0
(-1690 3410);
DISPLAY 0.659574 (-1690 3410);
PAINT MONO (-1690 3410);
DISPLAY INVISIBLE (-1690 3410);
FORCEPROP 1 LASTPIN (-1700 3400) BN 36
J 2
(-1650 3410);
DISPLAY 0.617021 (-1650 3410);
PAINT PINK (-1650 3410);
FORCEPROP 1 LAST PATH I74
J 2
(-1650 3400);
DISPLAY 0.936170 (-1650 3400);
PAINT GREEN (-1650 3400);
DISPLAY INVISIBLE (-1650 3400);
FORCEPROP 1 LAST HDL_TAP TRUE
J 2
(-1975 3275);
DISPLAY 1.234043 (-1975 3275);
PAINT GREEN (-1975 3275);
DISPLAY INVISIBLE (-1975 3275);
FORCEPROP 1 LAST BODY_TYPE PLUMBING
J 2
(-1650 3350);
DISPLAY 1.234043 (-1650 3350);
PAINT GREEN (-1650 3350);
DISPLAY INVISIBLE (-1650 3350);
FORCEPROP 2 LAST CDS_LIB mstr_standard
J 2
(-1650 3400);
DISPLAY 0.787234 (-1650 3400);
PAINT MONO (-1650 3400);
DISPLAY INVISIBLE (-1650 3400);
FORCEADD TAP..6
R 2
(-1650 3450);
FORCEPROP 3 LASTPIN (-1700 3450) SIG_NAME M_F_DQ<37>
J 0
(-1690 3460);
DISPLAY 0.659574 (-1690 3460);
PAINT MONO (-1690 3460);
DISPLAY INVISIBLE (-1690 3460);
FORCEPROP 1 LASTPIN (-1700 3450) BN 37
J 2
(-1650 3460);
DISPLAY 0.617021 (-1650 3460);
PAINT PINK (-1650 3460);
FORCEPROP 1 LAST PATH I75
J 2
(-1650 3450);
DISPLAY 0.936170 (-1650 3450);
PAINT GREEN (-1650 3450);
DISPLAY INVISIBLE (-1650 3450);
FORCEPROP 1 LAST HDL_TAP TRUE
J 2
(-1975 3325);
DISPLAY 1.234043 (-1975 3325);
PAINT GREEN (-1975 3325);
DISPLAY INVISIBLE (-1975 3325);
FORCEPROP 1 LAST BODY_TYPE PLUMBING
J 2
(-1650 3400);
DISPLAY 1.234043 (-1650 3400);
PAINT GREEN (-1650 3400);
DISPLAY INVISIBLE (-1650 3400);
FORCEPROP 2 LAST CDS_LIB mstr_standard
J 2
(-1650 3450);
DISPLAY 0.787234 (-1650 3450);
PAINT MONO (-1650 3450);
DISPLAY INVISIBLE (-1650 3450);
FORCEADD TAP..6
R 2
(-1650 3500);
FORCEPROP 3 LASTPIN (-1700 3500) SIG_NAME M_F_DQ<38>
J 0
(-1690 3510);
DISPLAY 0.659574 (-1690 3510);
PAINT MONO (-1690 3510);
DISPLAY INVISIBLE (-1690 3510);
FORCEPROP 1 LASTPIN (-1700 3500) BN 38
J 2
(-1650 3510);
DISPLAY 0.617021 (-1650 3510);
PAINT PINK (-1650 3510);
FORCEPROP 1 LAST PATH I76
J 2
(-1650 3500);
DISPLAY 0.936170 (-1650 3500);
PAINT GREEN (-1650 3500);
DISPLAY INVISIBLE (-1650 3500);
FORCEPROP 1 LAST HDL_TAP TRUE
J 2
(-1975 3375);
DISPLAY 1.234043 (-1975 3375);
PAINT GREEN (-1975 3375);
DISPLAY INVISIBLE (-1975 3375);
FORCEPROP 1 LAST BODY_TYPE PLUMBING
J 2
(-1650 3450);
DISPLAY 1.234043 (-1650 3450);
PAINT GREEN (-1650 3450);
DISPLAY INVISIBLE (-1650 3450);
FORCEPROP 2 LAST CDS_LIB mstr_standard
J 2
(-1650 3500);
DISPLAY 0.787234 (-1650 3500);
PAINT MONO (-1650 3500);
DISPLAY INVISIBLE (-1650 3500);
FORCEADD TAP..6
R 2
(-1650 3100);
FORCEPROP 3 LASTPIN (-1700 3100) SIG_NAME M_F_DQ<30>
J 0
(-1690 3110);
DISPLAY 0.659574 (-1690 3110);
PAINT MONO (-1690 3110);
DISPLAY INVISIBLE (-1690 3110);
FORCEPROP 1 LASTPIN (-1700 3100) BN 30
J 2
(-1650 3110);
DISPLAY 0.617021 (-1650 3110);
PAINT PINK (-1650 3110);
FORCEPROP 1 LAST PATH I77
J 2
(-1650 3100);
DISPLAY 0.936170 (-1650 3100);
PAINT GREEN (-1650 3100);
DISPLAY INVISIBLE (-1650 3100);
FORCEPROP 1 LAST HDL_TAP TRUE
J 2
(-1975 2975);
DISPLAY 1.234043 (-1975 2975);
PAINT GREEN (-1975 2975);
DISPLAY INVISIBLE (-1975 2975);
FORCEPROP 1 LAST BODY_TYPE PLUMBING
J 2
(-1650 3050);
DISPLAY 1.234043 (-1650 3050);
PAINT GREEN (-1650 3050);
DISPLAY INVISIBLE (-1650 3050);
FORCEPROP 2 LAST CDS_LIB mstr_standard
J 2
(-1650 3100);
DISPLAY 0.787234 (-1650 3100);
PAINT MONO (-1650 3100);
DISPLAY INVISIBLE (-1650 3100);
FORCEADD TAP..6
R 2
(-1650 3150);
FORCEPROP 3 LASTPIN (-1700 3150) SIG_NAME M_F_DQ<31>
J 0
(-1690 3160);
DISPLAY 0.659574 (-1690 3160);
PAINT MONO (-1690 3160);
DISPLAY INVISIBLE (-1690 3160);
FORCEPROP 1 LASTPIN (-1700 3150) BN 31
J 2
(-1650 3160);
DISPLAY 0.617021 (-1650 3160);
PAINT PINK (-1650 3160);
FORCEPROP 1 LAST PATH I78
J 2
(-1650 3150);
DISPLAY 0.936170 (-1650 3150);
PAINT GREEN (-1650 3150);
DISPLAY INVISIBLE (-1650 3150);
FORCEPROP 1 LAST HDL_TAP TRUE
J 2
(-1975 3025);
DISPLAY 1.234043 (-1975 3025);
PAINT GREEN (-1975 3025);
DISPLAY INVISIBLE (-1975 3025);
FORCEPROP 1 LAST BODY_TYPE PLUMBING
J 2
(-1650 3100);
DISPLAY 1.234043 (-1650 3100);
PAINT GREEN (-1650 3100);
DISPLAY INVISIBLE (-1650 3100);
FORCEPROP 2 LAST CDS_LIB mstr_standard
J 2
(-1650 3150);
DISPLAY 0.787234 (-1650 3150);
PAINT MONO (-1650 3150);
DISPLAY INVISIBLE (-1650 3150);
FORCEADD TAP..6
R 2
(-1650 3050);
FORCEPROP 3 LASTPIN (-1700 3050) SIG_NAME M_F_DQ<29>
J 0
(-1690 3060);
DISPLAY 0.659574 (-1690 3060);
PAINT MONO (-1690 3060);
DISPLAY INVISIBLE (-1690 3060);
FORCEPROP 1 LASTPIN (-1700 3050) BN 29
J 2
(-1650 3060);
DISPLAY 0.617021 (-1650 3060);
PAINT PINK (-1650 3060);
FORCEPROP 1 LAST PATH I79
J 2
(-1650 3050);
DISPLAY 0.936170 (-1650 3050);
PAINT GREEN (-1650 3050);
DISPLAY INVISIBLE (-1650 3050);
FORCEPROP 1 LAST HDL_TAP TRUE
J 2
(-1975 2925);
DISPLAY 1.234043 (-1975 2925);
PAINT GREEN (-1975 2925);
DISPLAY INVISIBLE (-1975 2925);
FORCEPROP 1 LAST BODY_TYPE PLUMBING
J 2
(-1650 3000);
DISPLAY 1.234043 (-1650 3000);
PAINT GREEN (-1650 3000);
DISPLAY INVISIBLE (-1650 3000);
FORCEPROP 2 LAST CDS_LIB mstr_standard
J 2
(-1650 3050);
DISPLAY 0.787234 (-1650 3050);
PAINT MONO (-1650 3050);
DISPLAY INVISIBLE (-1650 3050);
FORCEADD TAP..6
R 2
(900 4700);
FORCEPROP 3 LASTPIN (850 4700) SIG_NAME M_F_DQS_DN<13>
J 0
(860 4710);
DISPLAY 0.659574 (860 4710);
PAINT MONO (860 4710);
DISPLAY INVISIBLE (860 4710);
FORCEPROP 1 LASTPIN (850 4700) BN 13
J 2
(900 4710);
DISPLAY 0.617021 (900 4710);
PAINT PINK (900 4710);
FORCEPROP 1 LAST PATH I8
J 2
(900 4700);
DISPLAY 0.936170 (900 4700);
PAINT GREEN (900 4700);
DISPLAY INVISIBLE (900 4700);
FORCEPROP 1 LAST HDL_TAP TRUE
J 2
(575 4575);
DISPLAY 1.234043 (575 4575);
PAINT GREEN (575 4575);
DISPLAY INVISIBLE (575 4575);
FORCEPROP 1 LAST BODY_TYPE PLUMBING
J 2
(900 4650);
DISPLAY 1.234043 (900 4650);
PAINT GREEN (900 4650);
DISPLAY INVISIBLE (900 4650);
FORCEPROP 2 LAST CDS_LIB mstr_standard
J 0
(900 4700);
DISPLAY 0.787234 (900 4700);
PAINT MONO (900 4700);
DISPLAY INVISIBLE (900 4700);
FORCEADD TAP..6
R 2
(-1650 3200);
FORCEPROP 3 LASTPIN (-1700 3200) SIG_NAME M_F_DQ<32>
J 0
(-1690 3210);
DISPLAY 0.659574 (-1690 3210);
PAINT MONO (-1690 3210);
DISPLAY INVISIBLE (-1690 3210);
FORCEPROP 1 LASTPIN (-1700 3200) BN 32
J 2
(-1650 3210);
DISPLAY 0.617021 (-1650 3210);
PAINT PINK (-1650 3210);
FORCEPROP 1 LAST PATH I80
J 2
(-1650 3200);
DISPLAY 0.936170 (-1650 3200);
PAINT GREEN (-1650 3200);
DISPLAY INVISIBLE (-1650 3200);
FORCEPROP 1 LAST HDL_TAP TRUE
J 2
(-1975 3075);
DISPLAY 1.234043 (-1975 3075);
PAINT GREEN (-1975 3075);
DISPLAY INVISIBLE (-1975 3075);
FORCEPROP 1 LAST BODY_TYPE PLUMBING
J 2
(-1650 3150);
DISPLAY 1.234043 (-1650 3150);
PAINT GREEN (-1650 3150);
DISPLAY INVISIBLE (-1650 3150);
FORCEPROP 2 LAST CDS_LIB mstr_standard
J 2
(-1650 3200);
DISPLAY 0.787234 (-1650 3200);
PAINT MONO (-1650 3200);
DISPLAY INVISIBLE (-1650 3200);
FORCEADD TAP..6
R 2
(-1650 3250);
FORCEPROP 3 LASTPIN (-1700 3250) SIG_NAME M_F_DQ<33>
J 0
(-1690 3260);
DISPLAY 0.659574 (-1690 3260);
PAINT MONO (-1690 3260);
DISPLAY INVISIBLE (-1690 3260);
FORCEPROP 1 LASTPIN (-1700 3250) BN 33
J 2
(-1650 3260);
DISPLAY 0.617021 (-1650 3260);
PAINT PINK (-1650 3260);
FORCEPROP 1 LAST PATH I81
J 2
(-1650 3250);
DISPLAY 0.936170 (-1650 3250);
PAINT GREEN (-1650 3250);
DISPLAY INVISIBLE (-1650 3250);
FORCEPROP 1 LAST HDL_TAP TRUE
J 2
(-1975 3125);
DISPLAY 1.234043 (-1975 3125);
PAINT GREEN (-1975 3125);
DISPLAY INVISIBLE (-1975 3125);
FORCEPROP 1 LAST BODY_TYPE PLUMBING
J 2
(-1650 3200);
DISPLAY 1.234043 (-1650 3200);
PAINT GREEN (-1650 3200);
DISPLAY INVISIBLE (-1650 3200);
FORCEPROP 2 LAST CDS_LIB mstr_standard
J 2
(-1650 3250);
DISPLAY 0.787234 (-1650 3250);
PAINT MONO (-1650 3250);
DISPLAY INVISIBLE (-1650 3250);
FORCEADD TAP..6
R 2
(-1650 2850);
FORCEPROP 3 LASTPIN (-1700 2850) SIG_NAME M_F_DQ<25>
J 0
(-1690 2860);
DISPLAY 0.659574 (-1690 2860);
PAINT MONO (-1690 2860);
DISPLAY INVISIBLE (-1690 2860);
FORCEPROP 1 LASTPIN (-1700 2850) BN 25
J 2
(-1650 2860);
DISPLAY 0.617021 (-1650 2860);
PAINT PINK (-1650 2860);
FORCEPROP 1 LAST PATH I82
J 2
(-1650 2850);
DISPLAY 0.936170 (-1650 2850);
PAINT GREEN (-1650 2850);
DISPLAY INVISIBLE (-1650 2850);
FORCEPROP 1 LAST HDL_TAP TRUE
J 2
(-1975 2725);
DISPLAY 1.234043 (-1975 2725);
PAINT GREEN (-1975 2725);
DISPLAY INVISIBLE (-1975 2725);
FORCEPROP 1 LAST BODY_TYPE PLUMBING
J 2
(-1650 2800);
DISPLAY 1.234043 (-1650 2800);
PAINT GREEN (-1650 2800);
DISPLAY INVISIBLE (-1650 2800);
FORCEPROP 2 LAST CDS_LIB mstr_standard
J 2
(-1650 2850);
DISPLAY 0.787234 (-1650 2850);
PAINT MONO (-1650 2850);
DISPLAY INVISIBLE (-1650 2850);
FORCEADD TAP..6
R 2
(-1650 2800);
FORCEPROP 3 LASTPIN (-1700 2800) SIG_NAME M_F_DQ<24>
J 0
(-1690 2810);
DISPLAY 0.659574 (-1690 2810);
PAINT MONO (-1690 2810);
DISPLAY INVISIBLE (-1690 2810);
FORCEPROP 1 LASTPIN (-1700 2800) BN 24
J 2
(-1650 2810);
DISPLAY 0.617021 (-1650 2810);
PAINT PINK (-1650 2810);
FORCEPROP 1 LAST PATH I83
J 2
(-1650 2800);
DISPLAY 0.936170 (-1650 2800);
PAINT GREEN (-1650 2800);
DISPLAY INVISIBLE (-1650 2800);
FORCEPROP 1 LAST HDL_TAP TRUE
J 2
(-1975 2675);
DISPLAY 1.234043 (-1975 2675);
PAINT GREEN (-1975 2675);
DISPLAY INVISIBLE (-1975 2675);
FORCEPROP 1 LAST BODY_TYPE PLUMBING
J 2
(-1650 2750);
DISPLAY 1.234043 (-1650 2750);
PAINT GREEN (-1650 2750);
DISPLAY INVISIBLE (-1650 2750);
FORCEPROP 2 LAST CDS_LIB mstr_standard
J 2
(-1650 2800);
DISPLAY 0.787234 (-1650 2800);
PAINT MONO (-1650 2800);
DISPLAY INVISIBLE (-1650 2800);
FORCEADD TAP..6
R 2
(-1650 2900);
FORCEPROP 3 LASTPIN (-1700 2900) SIG_NAME M_F_DQ<26>
J 0
(-1690 2910);
DISPLAY 0.659574 (-1690 2910);
PAINT MONO (-1690 2910);
DISPLAY INVISIBLE (-1690 2910);
FORCEPROP 1 LASTPIN (-1700 2900) BN 26
J 2
(-1650 2910);
DISPLAY 0.617021 (-1650 2910);
PAINT PINK (-1650 2910);
FORCEPROP 1 LAST PATH I84
J 2
(-1650 2900);
DISPLAY 0.936170 (-1650 2900);
PAINT GREEN (-1650 2900);
DISPLAY INVISIBLE (-1650 2900);
FORCEPROP 1 LAST HDL_TAP TRUE
J 2
(-1975 2775);
DISPLAY 1.234043 (-1975 2775);
PAINT GREEN (-1975 2775);
DISPLAY INVISIBLE (-1975 2775);
FORCEPROP 1 LAST BODY_TYPE PLUMBING
J 2
(-1650 2850);
DISPLAY 1.234043 (-1650 2850);
PAINT GREEN (-1650 2850);
DISPLAY INVISIBLE (-1650 2850);
FORCEPROP 2 LAST CDS_LIB mstr_standard
J 2
(-1650 2900);
DISPLAY 0.787234 (-1650 2900);
PAINT MONO (-1650 2900);
DISPLAY INVISIBLE (-1650 2900);
FORCEADD TAP..6
R 2
(-1650 3000);
FORCEPROP 3 LASTPIN (-1700 3000) SIG_NAME M_F_DQ<28>
J 0
(-1690 3010);
DISPLAY 0.659574 (-1690 3010);
PAINT MONO (-1690 3010);
DISPLAY INVISIBLE (-1690 3010);
FORCEPROP 1 LASTPIN (-1700 3000) BN 28
J 2
(-1650 3010);
DISPLAY 0.617021 (-1650 3010);
PAINT PINK (-1650 3010);
FORCEPROP 1 LAST PATH I85
J 2
(-1650 3000);
DISPLAY 0.936170 (-1650 3000);
PAINT GREEN (-1650 3000);
DISPLAY INVISIBLE (-1650 3000);
FORCEPROP 1 LAST HDL_TAP TRUE
J 2
(-1975 2875);
DISPLAY 1.234043 (-1975 2875);
PAINT GREEN (-1975 2875);
DISPLAY INVISIBLE (-1975 2875);
FORCEPROP 1 LAST BODY_TYPE PLUMBING
J 2
(-1650 2950);
DISPLAY 1.234043 (-1650 2950);
PAINT GREEN (-1650 2950);
DISPLAY INVISIBLE (-1650 2950);
FORCEPROP 2 LAST CDS_LIB mstr_standard
J 2
(-1650 3000);
DISPLAY 0.787234 (-1650 3000);
PAINT MONO (-1650 3000);
DISPLAY INVISIBLE (-1650 3000);
FORCEADD TAP..6
R 2
(-1650 2950);
FORCEPROP 3 LASTPIN (-1700 2950) SIG_NAME M_F_DQ<27>
J 0
(-1690 2960);
DISPLAY 0.659574 (-1690 2960);
PAINT MONO (-1690 2960);
DISPLAY INVISIBLE (-1690 2960);
FORCEPROP 1 LASTPIN (-1700 2950) BN 27
J 2
(-1650 2960);
DISPLAY 0.617021 (-1650 2960);
PAINT PINK (-1650 2960);
FORCEPROP 1 LAST PATH I86
J 2
(-1650 2950);
DISPLAY 0.936170 (-1650 2950);
PAINT GREEN (-1650 2950);
DISPLAY INVISIBLE (-1650 2950);
FORCEPROP 1 LAST HDL_TAP TRUE
J 2
(-1975 2825);
DISPLAY 1.234043 (-1975 2825);
PAINT GREEN (-1975 2825);
DISPLAY INVISIBLE (-1975 2825);
FORCEPROP 1 LAST BODY_TYPE PLUMBING
J 2
(-1650 2900);
DISPLAY 1.234043 (-1650 2900);
PAINT GREEN (-1650 2900);
DISPLAY INVISIBLE (-1650 2900);
FORCEPROP 2 LAST CDS_LIB mstr_standard
J 2
(-1650 2950);
DISPLAY 0.787234 (-1650 2950);
PAINT MONO (-1650 2950);
DISPLAY INVISIBLE (-1650 2950);
FORCEADD TAP..6
R 2
(-1650 2550);
FORCEPROP 3 LASTPIN (-1700 2550) SIG_NAME M_F_DQ<19>
J 0
(-1690 2560);
DISPLAY 0.659574 (-1690 2560);
PAINT MONO (-1690 2560);
DISPLAY INVISIBLE (-1690 2560);
FORCEPROP 1 LASTPIN (-1700 2550) BN 19
J 2
(-1650 2560);
DISPLAY 0.617021 (-1650 2560);
PAINT PINK (-1650 2560);
FORCEPROP 1 LAST PATH I87
J 2
(-1650 2550);
DISPLAY 0.936170 (-1650 2550);
PAINT GREEN (-1650 2550);
DISPLAY INVISIBLE (-1650 2550);
FORCEPROP 1 LAST HDL_TAP TRUE
J 2
(-1975 2425);
DISPLAY 1.234043 (-1975 2425);
PAINT GREEN (-1975 2425);
DISPLAY INVISIBLE (-1975 2425);
FORCEPROP 1 LAST BODY_TYPE PLUMBING
J 2
(-1650 2500);
DISPLAY 1.234043 (-1650 2500);
PAINT GREEN (-1650 2500);
DISPLAY INVISIBLE (-1650 2500);
FORCEPROP 2 LAST CDS_LIB mstr_standard
J 2
(-1650 2550);
DISPLAY 0.787234 (-1650 2550);
PAINT MONO (-1650 2550);
DISPLAY INVISIBLE (-1650 2550);
FORCEADD TAP..6
R 2
(-1650 2600);
FORCEPROP 3 LASTPIN (-1700 2600) SIG_NAME M_F_DQ<20>
J 0
(-1690 2610);
DISPLAY 0.659574 (-1690 2610);
PAINT MONO (-1690 2610);
DISPLAY INVISIBLE (-1690 2610);
FORCEPROP 1 LASTPIN (-1700 2600) BN 20
J 2
(-1650 2610);
DISPLAY 0.617021 (-1650 2610);
PAINT PINK (-1650 2610);
FORCEPROP 1 LAST PATH I88
J 2
(-1650 2600);
DISPLAY 0.936170 (-1650 2600);
PAINT GREEN (-1650 2600);
DISPLAY INVISIBLE (-1650 2600);
FORCEPROP 1 LAST HDL_TAP TRUE
J 2
(-1975 2475);
DISPLAY 1.234043 (-1975 2475);
PAINT GREEN (-1975 2475);
DISPLAY INVISIBLE (-1975 2475);
FORCEPROP 1 LAST BODY_TYPE PLUMBING
J 2
(-1650 2550);
DISPLAY 1.234043 (-1650 2550);
PAINT GREEN (-1650 2550);
DISPLAY INVISIBLE (-1650 2550);
FORCEPROP 2 LAST CDS_LIB mstr_standard
J 2
(-1650 2600);
DISPLAY 0.787234 (-1650 2600);
PAINT MONO (-1650 2600);
DISPLAY INVISIBLE (-1650 2600);
FORCEADD TAP..6
R 2
(-1650 2650);
FORCEPROP 3 LASTPIN (-1700 2650) SIG_NAME M_F_DQ<21>
J 0
(-1690 2660);
DISPLAY 0.659574 (-1690 2660);
PAINT MONO (-1690 2660);
DISPLAY INVISIBLE (-1690 2660);
FORCEPROP 1 LASTPIN (-1700 2650) BN 21
J 2
(-1650 2660);
DISPLAY 0.617021 (-1650 2660);
PAINT PINK (-1650 2660);
FORCEPROP 1 LAST PATH I89
J 2
(-1650 2650);
DISPLAY 0.936170 (-1650 2650);
PAINT GREEN (-1650 2650);
DISPLAY INVISIBLE (-1650 2650);
FORCEPROP 1 LAST HDL_TAP TRUE
J 2
(-1975 2525);
DISPLAY 1.234043 (-1975 2525);
PAINT GREEN (-1975 2525);
DISPLAY INVISIBLE (-1975 2525);
FORCEPROP 1 LAST BODY_TYPE PLUMBING
J 2
(-1650 2600);
DISPLAY 1.234043 (-1650 2600);
PAINT GREEN (-1650 2600);
DISPLAY INVISIBLE (-1650 2600);
FORCEPROP 2 LAST CDS_LIB mstr_standard
J 2
(-1650 2650);
DISPLAY 0.787234 (-1650 2650);
PAINT MONO (-1650 2650);
DISPLAY INVISIBLE (-1650 2650);
FORCEADD TAP..6
R 2
(900 4600);
FORCEPROP 3 LASTPIN (850 4600) SIG_NAME M_F_DQS_DN<12>
J 0
(860 4610);
DISPLAY 0.659574 (860 4610);
PAINT MONO (860 4610);
DISPLAY INVISIBLE (860 4610);
FORCEPROP 1 LASTPIN (850 4600) BN 12
J 2
(900 4610);
DISPLAY 0.617021 (900 4610);
PAINT PINK (900 4610);
FORCEPROP 1 LAST PATH I9
J 2
(900 4600);
DISPLAY 0.936170 (900 4600);
PAINT GREEN (900 4600);
DISPLAY INVISIBLE (900 4600);
FORCEPROP 1 LAST HDL_TAP TRUE
J 2
(575 4475);
DISPLAY 1.234043 (575 4475);
PAINT GREEN (575 4475);
DISPLAY INVISIBLE (575 4475);
FORCEPROP 1 LAST BODY_TYPE PLUMBING
J 2
(900 4550);
DISPLAY 1.234043 (900 4550);
PAINT GREEN (900 4550);
DISPLAY INVISIBLE (900 4550);
FORCEPROP 2 LAST CDS_LIB mstr_standard
J 0
(900 4600);
DISPLAY 0.787234 (900 4600);
PAINT MONO (900 4600);
DISPLAY INVISIBLE (900 4600);
FORCEADD TAP..6
R 2
(-1650 2750);
FORCEPROP 3 LASTPIN (-1700 2750) SIG_NAME M_F_DQ<23>
J 0
(-1690 2760);
DISPLAY 0.659574 (-1690 2760);
PAINT MONO (-1690 2760);
DISPLAY INVISIBLE (-1690 2760);
FORCEPROP 1 LASTPIN (-1700 2750) BN 23
J 2
(-1650 2760);
DISPLAY 0.617021 (-1650 2760);
PAINT PINK (-1650 2760);
FORCEPROP 1 LAST PATH I90
J 2
(-1650 2750);
DISPLAY 0.936170 (-1650 2750);
PAINT GREEN (-1650 2750);
DISPLAY INVISIBLE (-1650 2750);
FORCEPROP 1 LAST HDL_TAP TRUE
J 2
(-1975 2625);
DISPLAY 1.234043 (-1975 2625);
PAINT GREEN (-1975 2625);
DISPLAY INVISIBLE (-1975 2625);
FORCEPROP 1 LAST BODY_TYPE PLUMBING
J 2
(-1650 2700);
DISPLAY 1.234043 (-1650 2700);
PAINT GREEN (-1650 2700);
DISPLAY INVISIBLE (-1650 2700);
FORCEPROP 2 LAST CDS_LIB mstr_standard
J 2
(-1650 2750);
DISPLAY 0.787234 (-1650 2750);
PAINT MONO (-1650 2750);
DISPLAY INVISIBLE (-1650 2750);
FORCEADD TAP..6
R 2
(-1650 2700);
FORCEPROP 3 LASTPIN (-1700 2700) SIG_NAME M_F_DQ<22>
J 0
(-1690 2710);
DISPLAY 0.659574 (-1690 2710);
PAINT MONO (-1690 2710);
DISPLAY INVISIBLE (-1690 2710);
FORCEPROP 1 LASTPIN (-1700 2700) BN 22
J 2
(-1650 2710);
DISPLAY 0.617021 (-1650 2710);
PAINT PINK (-1650 2710);
FORCEPROP 1 LAST PATH I91
J 2
(-1650 2700);
DISPLAY 0.936170 (-1650 2700);
PAINT GREEN (-1650 2700);
DISPLAY INVISIBLE (-1650 2700);
FORCEPROP 1 LAST HDL_TAP TRUE
J 2
(-1975 2575);
DISPLAY 1.234043 (-1975 2575);
PAINT GREEN (-1975 2575);
DISPLAY INVISIBLE (-1975 2575);
FORCEPROP 1 LAST BODY_TYPE PLUMBING
J 2
(-1650 2650);
DISPLAY 1.234043 (-1650 2650);
PAINT GREEN (-1650 2650);
DISPLAY INVISIBLE (-1650 2650);
FORCEPROP 2 LAST CDS_LIB mstr_standard
J 2
(-1650 2700);
DISPLAY 0.787234 (-1650 2700);
PAINT MONO (-1650 2700);
DISPLAY INVISIBLE (-1650 2700);
FORCEADD TAP..6
R 2
(-1650 2300);
FORCEPROP 3 LASTPIN (-1700 2300) SIG_NAME M_F_DQ<14>
J 0
(-1690 2310);
DISPLAY 0.659574 (-1690 2310);
PAINT MONO (-1690 2310);
DISPLAY INVISIBLE (-1690 2310);
FORCEPROP 1 LASTPIN (-1700 2300) BN 14
J 2
(-1650 2310);
DISPLAY 0.617021 (-1650 2310);
PAINT PINK (-1650 2310);
FORCEPROP 1 LAST PATH I92
J 2
(-1650 2300);
DISPLAY 0.936170 (-1650 2300);
PAINT GREEN (-1650 2300);
DISPLAY INVISIBLE (-1650 2300);
FORCEPROP 1 LAST HDL_TAP TRUE
J 2
(-1975 2175);
DISPLAY 1.234043 (-1975 2175);
PAINT GREEN (-1975 2175);
DISPLAY INVISIBLE (-1975 2175);
FORCEPROP 1 LAST BODY_TYPE PLUMBING
J 2
(-1650 2250);
DISPLAY 1.234043 (-1650 2250);
PAINT GREEN (-1650 2250);
DISPLAY INVISIBLE (-1650 2250);
FORCEPROP 2 LAST CDS_LIB mstr_standard
J 2
(-1650 2300);
DISPLAY 0.787234 (-1650 2300);
PAINT MONO (-1650 2300);
DISPLAY INVISIBLE (-1650 2300);
FORCEADD TAP..6
R 2
(-1650 2350);
FORCEPROP 3 LASTPIN (-1700 2350) SIG_NAME M_F_DQ<15>
J 0
(-1690 2360);
DISPLAY 0.659574 (-1690 2360);
PAINT MONO (-1690 2360);
DISPLAY INVISIBLE (-1690 2360);
FORCEPROP 1 LASTPIN (-1700 2350) BN 15
J 2
(-1650 2360);
DISPLAY 0.617021 (-1650 2360);
PAINT PINK (-1650 2360);
FORCEPROP 1 LAST PATH I93
J 2
(-1650 2350);
DISPLAY 0.936170 (-1650 2350);
PAINT GREEN (-1650 2350);
DISPLAY INVISIBLE (-1650 2350);
FORCEPROP 1 LAST HDL_TAP TRUE
J 2
(-1975 2225);
DISPLAY 1.234043 (-1975 2225);
PAINT GREEN (-1975 2225);
DISPLAY INVISIBLE (-1975 2225);
FORCEPROP 1 LAST BODY_TYPE PLUMBING
J 2
(-1650 2300);
DISPLAY 1.234043 (-1650 2300);
PAINT GREEN (-1650 2300);
DISPLAY INVISIBLE (-1650 2300);
FORCEPROP 2 LAST CDS_LIB mstr_standard
J 2
(-1650 2350);
DISPLAY 0.787234 (-1650 2350);
PAINT MONO (-1650 2350);
DISPLAY INVISIBLE (-1650 2350);
FORCEADD TAP..6
R 2
(-1650 2450);
FORCEPROP 3 LASTPIN (-1700 2450) SIG_NAME M_F_DQ<17>
J 0
(-1690 2460);
DISPLAY 0.659574 (-1690 2460);
PAINT MONO (-1690 2460);
DISPLAY INVISIBLE (-1690 2460);
FORCEPROP 1 LASTPIN (-1700 2450) BN 17
J 2
(-1650 2460);
DISPLAY 0.617021 (-1650 2460);
PAINT PINK (-1650 2460);
FORCEPROP 1 LAST PATH I94
J 2
(-1650 2450);
DISPLAY 0.936170 (-1650 2450);
PAINT GREEN (-1650 2450);
DISPLAY INVISIBLE (-1650 2450);
FORCEPROP 1 LAST HDL_TAP TRUE
J 2
(-1975 2325);
DISPLAY 1.234043 (-1975 2325);
PAINT GREEN (-1975 2325);
DISPLAY INVISIBLE (-1975 2325);
FORCEPROP 1 LAST BODY_TYPE PLUMBING
J 2
(-1650 2400);
DISPLAY 1.234043 (-1650 2400);
PAINT GREEN (-1650 2400);
DISPLAY INVISIBLE (-1650 2400);
FORCEPROP 2 LAST CDS_LIB mstr_standard
J 2
(-1650 2450);
DISPLAY 0.787234 (-1650 2450);
PAINT MONO (-1650 2450);
DISPLAY INVISIBLE (-1650 2450);
FORCEADD TAP..6
R 2
(-1650 2400);
FORCEPROP 3 LASTPIN (-1700 2400) SIG_NAME M_F_DQ<16>
J 0
(-1690 2410);
DISPLAY 0.659574 (-1690 2410);
PAINT MONO (-1690 2410);
DISPLAY INVISIBLE (-1690 2410);
FORCEPROP 1 LASTPIN (-1700 2400) BN 16
J 2
(-1650 2410);
DISPLAY 0.617021 (-1650 2410);
PAINT PINK (-1650 2410);
FORCEPROP 1 LAST PATH I95
J 2
(-1650 2400);
DISPLAY 0.936170 (-1650 2400);
PAINT GREEN (-1650 2400);
DISPLAY INVISIBLE (-1650 2400);
FORCEPROP 1 LAST HDL_TAP TRUE
J 2
(-1975 2275);
DISPLAY 1.234043 (-1975 2275);
PAINT GREEN (-1975 2275);
DISPLAY INVISIBLE (-1975 2275);
FORCEPROP 1 LAST BODY_TYPE PLUMBING
J 2
(-1650 2350);
DISPLAY 1.234043 (-1650 2350);
PAINT GREEN (-1650 2350);
DISPLAY INVISIBLE (-1650 2350);
FORCEPROP 2 LAST CDS_LIB mstr_standard
J 2
(-1650 2400);
DISPLAY 0.787234 (-1650 2400);
PAINT MONO (-1650 2400);
DISPLAY INVISIBLE (-1650 2400);
FORCEADD TAP..6
R 2
(-1650 2500);
FORCEPROP 3 LASTPIN (-1700 2500) SIG_NAME M_F_DQ<18>
J 0
(-1690 2510);
DISPLAY 0.659574 (-1690 2510);
PAINT MONO (-1690 2510);
DISPLAY INVISIBLE (-1690 2510);
FORCEPROP 1 LASTPIN (-1700 2500) BN 18
J 2
(-1650 2510);
DISPLAY 0.617021 (-1650 2510);
PAINT PINK (-1650 2510);
FORCEPROP 1 LAST PATH I96
J 2
(-1650 2500);
DISPLAY 0.936170 (-1650 2500);
PAINT GREEN (-1650 2500);
DISPLAY INVISIBLE (-1650 2500);
FORCEPROP 1 LAST HDL_TAP TRUE
J 2
(-1975 2375);
DISPLAY 1.234043 (-1975 2375);
PAINT GREEN (-1975 2375);
DISPLAY INVISIBLE (-1975 2375);
FORCEPROP 1 LAST BODY_TYPE PLUMBING
J 2
(-1650 2450);
DISPLAY 1.234043 (-1650 2450);
PAINT GREEN (-1650 2450);
DISPLAY INVISIBLE (-1650 2450);
FORCEPROP 2 LAST CDS_LIB mstr_standard
J 2
(-1650 2500);
DISPLAY 0.787234 (-1650 2500);
PAINT MONO (-1650 2500);
DISPLAY INVISIBLE (-1650 2500);
FORCEADD TAP..6
R 2
(-1650 2250);
FORCEPROP 3 LASTPIN (-1700 2250) SIG_NAME M_F_DQ<13>
J 0
(-1690 2260);
DISPLAY 0.659574 (-1690 2260);
PAINT MONO (-1690 2260);
DISPLAY INVISIBLE (-1690 2260);
FORCEPROP 1 LASTPIN (-1700 2250) BN 13
J 2
(-1650 2260);
DISPLAY 0.617021 (-1650 2260);
PAINT PINK (-1650 2260);
FORCEPROP 1 LAST PATH I97
J 2
(-1650 2250);
DISPLAY 0.936170 (-1650 2250);
PAINT GREEN (-1650 2250);
DISPLAY INVISIBLE (-1650 2250);
FORCEPROP 1 LAST HDL_TAP TRUE
J 2
(-1975 2125);
DISPLAY 1.234043 (-1975 2125);
PAINT GREEN (-1975 2125);
DISPLAY INVISIBLE (-1975 2125);
FORCEPROP 1 LAST BODY_TYPE PLUMBING
J 2
(-1650 2200);
DISPLAY 1.234043 (-1650 2200);
PAINT GREEN (-1650 2200);
DISPLAY INVISIBLE (-1650 2200);
FORCEPROP 2 LAST CDS_LIB mstr_standard
J 2
(-1650 2250);
DISPLAY 0.787234 (-1650 2250);
PAINT MONO (-1650 2250);
DISPLAY INVISIBLE (-1650 2250);
FORCEADD TAP..6
R 2
(-1650 2150);
FORCEPROP 3 LASTPIN (-1700 2150) SIG_NAME M_F_DQ<11>
J 0
(-1690 2160);
DISPLAY 0.659574 (-1690 2160);
PAINT MONO (-1690 2160);
DISPLAY INVISIBLE (-1690 2160);
FORCEPROP 1 LASTPIN (-1700 2150) BN 11
J 2
(-1650 2160);
DISPLAY 0.617021 (-1650 2160);
PAINT PINK (-1650 2160);
FORCEPROP 1 LAST PATH I98
J 2
(-1650 2150);
DISPLAY 0.936170 (-1650 2150);
PAINT GREEN (-1650 2150);
DISPLAY INVISIBLE (-1650 2150);
FORCEPROP 1 LAST HDL_TAP TRUE
J 2
(-1975 2025);
DISPLAY 1.234043 (-1975 2025);
PAINT GREEN (-1975 2025);
DISPLAY INVISIBLE (-1975 2025);
FORCEPROP 1 LAST BODY_TYPE PLUMBING
J 2
(-1650 2100);
DISPLAY 1.234043 (-1650 2100);
PAINT GREEN (-1650 2100);
DISPLAY INVISIBLE (-1650 2100);
FORCEPROP 2 LAST CDS_LIB mstr_standard
J 2
(-1650 2150);
DISPLAY 0.787234 (-1650 2150);
PAINT MONO (-1650 2150);
DISPLAY INVISIBLE (-1650 2150);
FORCEADD TAP..6
R 2
(-1650 2200);
FORCEPROP 3 LASTPIN (-1700 2200) SIG_NAME M_F_DQ<12>
J 0
(-1690 2210);
DISPLAY 0.659574 (-1690 2210);
PAINT MONO (-1690 2210);
DISPLAY INVISIBLE (-1690 2210);
FORCEPROP 1 LASTPIN (-1700 2200) BN 12
J 2
(-1650 2210);
DISPLAY 0.617021 (-1650 2210);
PAINT PINK (-1650 2210);
FORCEPROP 1 LAST PATH I99
J 2
(-1650 2200);
DISPLAY 0.936170 (-1650 2200);
PAINT GREEN (-1650 2200);
DISPLAY INVISIBLE (-1650 2200);
FORCEPROP 1 LAST HDL_TAP TRUE
J 2
(-1975 2075);
DISPLAY 1.234043 (-1975 2075);
PAINT GREEN (-1975 2075);
DISPLAY INVISIBLE (-1975 2075);
FORCEPROP 1 LAST BODY_TYPE PLUMBING
J 2
(-1650 2150);
DISPLAY 1.234043 (-1650 2150);
PAINT GREEN (-1650 2150);
DISPLAY INVISIBLE (-1650 2150);
FORCEPROP 2 LAST CDS_LIB mstr_standard
J 2
(-1650 2200);
DISPLAY 0.787234 (-1650 2200);
PAINT MONO (-1650 2200);
DISPLAY INVISIBLE (-1650 2200);
FORCEADD INTEL_CORP_BPAGE..1
(2650 500);
FORCEPROP 1 LAST CDS_CON_LAST_MODIFIED Fri Jun 16 17:48:21 2017
J 0
(1225 825);
DISPLAY 0.787234 (1225 825);
PAINT ORANGE (1225 825);
DISPLAY INVISIBLE (1225 825);
FORCEPROP 1 LAST CUSTOM_TXT_CDS <CURRENT_DESIGN_SHEET> OF <TOTAL_DESIGN_SHEETS>
J 0
(2150 525);
PAINT ORANGE (2150 525);
FORCEPROP 1 LAST CUSTOM_TXT_CDS <CON_LAST_MODIFIED>
J 0
(-1350 600);
PAINT ORANGE (-1350 600);
FORCEPROP 2 LAST CUSTOM_TXT_CDS <XR_PAGE_TITLE>
J 0
(-5240 5750);
DISPLAY 0.638298 (-5240 5750);
PAINT PINK (-5240 5750);
DISPLAY INVISIBLE (-5240 5750);
FORCEPROP 1 LAST SCH_TITLE CPU0 DDR4 CH F DIMM1
J 0
(-5300 550);
DISPLAY 1.212766 (-5300 550);
PAINT WHITE (-5300 550);
FORCEPROP 1 LAST COMMENT_BODY TRUE
J 0
(2660 510);
DISPLAY 0.382979 (2660 510);
PAINT GREEN (2660 510);
DISPLAY INVISIBLE (2660 510);
FORCEPROP 2 LAST CDS_LIB mstr_symbols
J 0
(2650 500);
DISPLAY 0.787234 (2650 500);
PAINT MONO (2650 500);
DISPLAY INVISIBLE (2650 500);
FORCEPROP 2 LAST PAGE_BORDER TRUE
J 0
(-5240 5750);
DISPLAY 0.680851 (-5240 5750);
PAINT PINK (-5240 5750);
DISPLAY INVISIBLE (-5240 5750);
FORCEPROP 2 LAST CDS_XR_PAGE_TITLE CR-54 : @BASEBOARD_FAB2_LIB.BASEBOARD_FAB2(SCH_1):PAGE54
J 0
(-5240 5750);
DISPLAY 0.638298 (-5240 5750);
PAINT PINK (-5240 5750);
DISPLAY INVISIBLE (-5240 5750);
FORCEADD BOM_NOTE..1
(-5025 5250);
FORCEPROP 0 LAST L1 UNSTUFF FOR SKU B
J 0
(-5175 5150);
DISPLAY 1.063830 (-5175 5150);
PAINT WHITE (-5175 5150);
FORCEPROP 2 LAST ROOM SB_HEADERS
J 0
(-5175 5225);
DISPLAY 1.361702 (-5175 5225);
PAINT ORANGE (-5175 5225);
DISPLAY INVISIBLE (-5175 5225);
FORCEPROP 1 LAST COMMENT_BODY TRUE
J 0
(-5000 5350);
DISPLAY 1.319149 (-5000 5350);
PAINT ORANGE (-5000 5350);
DISPLAY INVISIBLE (-5000 5350);
FORCEPROP 2 LAST CDS_LIB mstr_symbols
J 0
(-5025 5250);
PAINT ORANGE (-5025 5250);
DISPLAY INVISIBLE (-5025 5250);
FORCEPROP 2 LAST BOM_COST SB
J 0
(-5175 5225);
DISPLAY 1.361702 (-5175 5225);
PAINT ORANGE (-5175 5225);
DISPLAY INVISIBLE (-5175 5225);
WIRE 16 -1 (-1150 2425)(-1150 2300);
WIRE 16 -1 (-1150 2300)(-750 2300);
WIRE 16 -1 (-750 2250)(-750 2300);
WIRE 16 -1 (-750 2300)(-550 2300);
WIRE 16 -1 (-750 2200)(-750 2250);
WIRE 16 -1 (-750 2250)(-550 2250);
WIRE 16 -1 (-750 2150)(-750 2200);
WIRE 16 -1 (-750 2200)(-550 2200);
WIRE 16 -1 (-750 2100)(-750 2150);
WIRE 16 -1 (-750 2150)(-550 2150);
WIRE 16 -1 (-750 2050)(-750 2100);
WIRE 16 -1 (-750 2100)(-550 2100);
WIRE 16 -1 (-750 2000)(-750 2050);
WIRE 16 -1 (-750 2050)(-550 2050);
WIRE 16 -1 (-750 1950)(-750 2000);
WIRE 16 -1 (-750 2000)(-550 2000);
WIRE 16 -1 (-750 1900)(-750 1950);
WIRE 16 -1 (-750 1950)(-550 1950);
WIRE 16 -1 (-750 1850)(-750 1900);
WIRE 16 -1 (-750 1900)(-550 1900);
WIRE 16 -1 (-750 1800)(-750 1850);
WIRE 16 -1 (-750 1850)(-550 1850);
WIRE 16 -1 (-750 1750)(-750 1800);
WIRE 16 -1 (-750 1800)(-550 1800);
WIRE 16 -1 (-750 1700)(-750 1750);
WIRE 16 -1 (-750 1750)(-550 1750);
WIRE 16 -1 (-750 1650)(-750 1700);
WIRE 16 -1 (-750 1700)(-550 1700);
WIRE 16 -1 (-750 1600)(-750 1650);
WIRE 16 -1 (-750 1650)(-550 1650);
WIRE 16 -1 (-750 1550)(-750 1600);
WIRE 16 -1 (-750 1600)(-550 1600);
WIRE 16 -1 (-750 1500)(-750 1550);
WIRE 16 -1 (-750 1550)(-550 1550);
WIRE 16 -1 (-750 1450)(-750 1500);
WIRE 16 -1 (-750 1500)(-550 1500);
WIRE 16 -1 (-750 1400)(-750 1450);
WIRE 16 -1 (-750 1450)(-550 1450);
WIRE 16 -1 (-750 1350)(-750 1400);
WIRE 16 -1 (-750 1400)(-550 1400);
WIRE 16 -1 (-750 1300)(-750 1350);
WIRE 16 -1 (-750 1350)(-550 1350);
WIRE 16 -1 (-750 1250)(-750 1300);
WIRE 16 -1 (-750 1300)(-550 1300);
WIRE 16 -1 (-750 1200)(-750 1250);
WIRE 16 -1 (-750 1250)(-550 1250);
WIRE 16 -1 (-750 1150)(-750 1200);
WIRE 16 -1 (-750 1200)(-550 1200);
WIRE 16 -1 (-750 1100)(-750 1150);
WIRE 16 -1 (-750 1150)(-550 1150);
WIRE 16 -1 (-750 1050)(-750 1100);
WIRE 16 -1 (-750 1100)(-550 1100);
WIRE 16 -1 (-750 1050)(-550 1050);
WIRE 16 -1 (-900 2550)(-900 2450);
WIRE 16 -1 (-900 2450)(-750 2450);
WIRE 16 -1 (-750 2400)(-750 2450);
WIRE 16 -1 (-750 2450)(-550 2450);
WIRE 16 -1 (-550 2400)(-750 2400);
WIRE 16 -1 (2500 1300)(2500 1400);
WIRE 16 -1 (2500 1400)(2500 1450);
WIRE 16 -1 (2500 1400)(2300 1400);
WIRE 16 -1 (2500 1450)(2500 1500);
WIRE 16 -1 (2500 1450)(2300 1450);
WIRE 16 -1 (2500 1500)(2500 1550);
WIRE 16 -1 (2500 1500)(2300 1500);
WIRE 16 -1 (2500 1550)(2500 1600);
WIRE 16 -1 (2500 1550)(2300 1550);
WIRE 16 -1 (2500 1600)(2500 1650);
WIRE 16 -1 (2500 1600)(2300 1600);
WIRE 16 -1 (2500 1650)(2500 1700);
WIRE 16 -1 (2500 1650)(2300 1650);
WIRE 16 -1 (2500 1700)(2500 1750);
WIRE 16 -1 (2500 1700)(2300 1700);
WIRE 16 -1 (2500 1750)(2500 1800);
WIRE 16 -1 (2500 1750)(2300 1750);
WIRE 16 -1 (2500 1800)(2500 1850);
WIRE 16 -1 (2500 1800)(2300 1800);
WIRE 16 -1 (2500 1850)(2500 1900);
WIRE 16 -1 (2500 1850)(2300 1850);
WIRE 16 -1 (2500 1900)(2500 1950);
WIRE 16 -1 (2500 1900)(2300 1900);
WIRE 16 -1 (2500 1950)(2500 2000);
WIRE 16 -1 (2500 1950)(2300 1950);
WIRE 16 -1 (2500 2000)(2500 2050);
WIRE 16 -1 (2500 2000)(2300 2000);
WIRE 16 -1 (2500 2050)(2500 2100);
WIRE 16 -1 (2500 2050)(2300 2050);
WIRE 16 -1 (2500 2100)(2500 2150);
WIRE 16 -1 (2500 2100)(2300 2100);
WIRE 16 -1 (2500 2150)(2500 2200);
WIRE 16 -1 (2500 2150)(2300 2150);
WIRE 16 -1 (2500 2200)(2500 2250);
WIRE 16 -1 (2500 2200)(2300 2200);
WIRE 16 -1 (2500 2250)(2500 2300);
WIRE 16 -1 (2500 2250)(2300 2250);
WIRE 16 -1 (2500 2300)(2500 2350);
WIRE 16 -1 (2500 2300)(2300 2300);
WIRE 16 -1 (2500 2350)(2500 2400);
WIRE 16 -1 (2500 2350)(2300 2350);
WIRE 16 -1 (2500 2400)(2500 2450);
WIRE 16 -1 (2500 2400)(2300 2400);
WIRE 16 -1 (2500 2450)(2500 2500);
WIRE 16 -1 (2500 2450)(2300 2450);
WIRE 16 -1 (2500 2500)(2500 2550);
WIRE 16 -1 (2500 2500)(2300 2500);
WIRE 16 -1 (2500 2550)(2500 2600);
WIRE 16 -1 (2500 2550)(2300 2550);
WIRE 16 -1 (2500 2600)(2500 2650);
WIRE 16 -1 (2500 2600)(2300 2600);
WIRE 16 -1 (2500 2650)(2500 2700);
WIRE 16 -1 (2500 2650)(2300 2650);
WIRE 16 -1 (2500 2700)(2500 2750);
WIRE 16 -1 (2500 2700)(2300 2700);
WIRE 16 -1 (2500 2750)(2500 2800);
WIRE 16 -1 (2500 2750)(2300 2750);
WIRE 16 -1 (2500 2800)(2500 2850);
WIRE 16 -1 (2500 2800)(2300 2800);
WIRE 16 -1 (2500 2850)(2500 2900);
WIRE 16 -1 (2500 2850)(2300 2850);
WIRE 16 -1 (2500 2900)(2500 2950);
WIRE 16 -1 (2500 2900)(2300 2900);
WIRE 16 -1 (2500 2950)(2500 3000);
WIRE 16 -1 (2500 2950)(2300 2950);
WIRE 16 -1 (2500 3000)(2500 3050);
WIRE 16 -1 (2500 3000)(2300 3000);
WIRE 16 -1 (2500 3050)(2500 3100);
WIRE 16 -1 (2500 3050)(2300 3050);
WIRE 16 -1 (2500 3100)(2500 3150);
WIRE 16 -1 (2500 3100)(2300 3100);
WIRE 16 -1 (2500 3150)(2500 3200);
WIRE 16 -1 (2500 3150)(2300 3150);
WIRE 16 -1 (2500 3200)(2500 3250);
WIRE 16 -1 (2500 3200)(2300 3200);
WIRE 16 -1 (2500 3250)(2500 3300);
WIRE 16 -1 (2500 3250)(2300 3250);
WIRE 16 -1 (2500 3300)(2500 3350);
WIRE 16 -1 (2500 3300)(2300 3300);
WIRE 16 -1 (2500 3350)(2500 3400);
WIRE 16 -1 (2500 3350)(2300 3350);
WIRE 16 -1 (2500 3400)(2500 3450);
WIRE 16 -1 (2500 3400)(2300 3400);
WIRE 16 -1 (2500 3450)(2500 3500);
WIRE 16 -1 (2500 3450)(2300 3450);
WIRE 16 -1 (2500 3500)(2500 3550);
WIRE 16 -1 (2500 3500)(2300 3500);
WIRE 16 -1 (2500 3550)(2500 3600);
WIRE 16 -1 (2500 3550)(2300 3550);
WIRE 16 -1 (2500 3600)(2500 3650);
WIRE 16 -1 (2500 3600)(2300 3600);
WIRE 16 -1 (2500 3650)(2500 3700);
WIRE 16 -1 (2500 3650)(2300 3650);
WIRE 16 -1 (2500 3700)(2300 3700);
WIRE 16 -1 (-4600 1300)(-4600 1200);
WIRE 16 -1 (-750 2850)(-750 2750);
WIRE 16 -1 (-750 2700)(-750 2750);
WIRE 16 -1 (-750 2750)(-550 2750);
WIRE 16 -1 (-750 2650)(-750 2700);
WIRE 16 -1 (-750 2700)(-550 2700);
WIRE 16 -1 (-750 2600)(-750 2650);
WIRE 16 -1 (-750 2650)(-550 2650);
WIRE 16 -1 (-750 2550)(-750 2600);
WIRE 16 -1 (-750 2600)(-550 2600);
WIRE 16 -1 (-750 2550)(-550 2550);
WIRE 16 -1 (-5200 1950)(-5200 2050);
WIRE 16 -1 (-3100 1950)(-5200 1950);
WIRE 16 -1 (-3100 1900)(-3100 1950);
WIRE 16 -1 (-2900 1950)(-3100 1950);
WIRE 16 -1 (-3100 1800)(-3100 1900);
WIRE 16 -1 (-3100 1900)(-2900 1900);
WIRE 16 -1 (-2900 1800)(-3100 1800);
WIRE 16 -1 (-5200 1850)(-5200 1800);
WIRE 16 -1 (-2900 1850)(-5200 1850);
WIRE 16 -1 (650 2750)(650 2925);
WIRE 16 -1 (650 2700)(650 2750);
WIRE 16 -1 (450 2750)(650 2750);
WIRE 16 -1 (450 2700)(650 2700);
WIRE 16 -1 (1100 1300)(1100 1400);
WIRE 16 -1 (1100 1400)(1100 1450);
WIRE 16 -1 (1100 1400)(1300 1400);
WIRE 16 -1 (1100 1450)(1100 1500);
WIRE 16 -1 (1100 1450)(1300 1450);
WIRE 16 -1 (1100 1500)(1100 1550);
WIRE 16 -1 (1100 1500)(1300 1500);
WIRE 16 -1 (1100 1550)(1100 1600);
WIRE 16 -1 (1100 1550)(1300 1550);
WIRE 16 -1 (1100 1600)(1100 1650);
WIRE 16 -1 (1100 1600)(1300 1600);
WIRE 16 -1 (1100 1650)(1100 1700);
WIRE 16 -1 (1100 1650)(1300 1650);
WIRE 16 -1 (1100 1700)(1100 1750);
WIRE 16 -1 (1100 1700)(1300 1700);
WIRE 16 -1 (1100 1750)(1100 1800);
WIRE 16 -1 (1100 1750)(1300 1750);
WIRE 16 -1 (1100 1800)(1100 1850);
WIRE 16 -1 (1100 1800)(1300 1800);
WIRE 16 -1 (1100 1850)(1100 1900);
WIRE 16 -1 (1100 1850)(1300 1850);
WIRE 16 -1 (1100 1900)(1100 1950);
WIRE 16 -1 (1100 1900)(1300 1900);
WIRE 16 -1 (1100 1950)(1100 2000);
WIRE 16 -1 (1100 1950)(1300 1950);
WIRE 16 -1 (1100 2000)(1100 2050);
WIRE 16 -1 (1100 2000)(1300 2000);
WIRE 16 -1 (1100 2050)(1100 2100);
WIRE 16 -1 (1100 2050)(1300 2050);
WIRE 16 -1 (1100 2100)(1100 2150);
WIRE 16 -1 (1100 2100)(1300 2100);
WIRE 16 -1 (1100 2150)(1100 2200);
WIRE 16 -1 (1100 2150)(1300 2150);
WIRE 16 -1 (1100 2200)(1100 2250);
WIRE 16 -1 (1100 2200)(1300 2200);
WIRE 16 -1 (1100 2250)(1100 2300);
WIRE 16 -1 (1100 2250)(1300 2250);
WIRE 16 -1 (1100 2300)(1100 2350);
WIRE 16 -1 (1100 2300)(1300 2300);
WIRE 16 -1 (1100 2350)(1100 2400);
WIRE 16 -1 (1100 2350)(1300 2350);
WIRE 16 -1 (1100 2400)(1100 2450);
WIRE 16 -1 (1100 2400)(1300 2400);
WIRE 16 -1 (1100 2450)(1100 2500);
WIRE 16 -1 (1100 2450)(1300 2450);
WIRE 16 -1 (1100 2500)(1100 2550);
WIRE 16 -1 (1100 2500)(1300 2500);
WIRE 16 -1 (1100 2550)(1100 2600);
WIRE 16 -1 (1100 2550)(1300 2550);
WIRE 16 -1 (1100 2600)(1100 2650);
WIRE 16 -1 (1100 2600)(1300 2600);
WIRE 16 -1 (1100 2650)(1100 2700);
WIRE 16 -1 (1100 2650)(1300 2650);
WIRE 16 -1 (1100 2700)(1100 2750);
WIRE 16 -1 (1100 2700)(1300 2700);
WIRE 16 -1 (1100 2750)(1100 2800);
WIRE 16 -1 (1100 2750)(1300 2750);
WIRE 16 -1 (1100 2800)(1100 2850);
WIRE 16 -1 (1100 2800)(1300 2800);
WIRE 16 -1 (1100 2850)(1100 2900);
WIRE 16 -1 (1100 2850)(1300 2850);
WIRE 16 -1 (1100 2900)(1100 2950);
WIRE 16 -1 (1100 2900)(1300 2900);
WIRE 16 -1 (1100 2950)(1100 3000);
WIRE 16 -1 (1100 2950)(1300 2950);
WIRE 16 -1 (1100 3000)(1100 3050);
WIRE 16 -1 (1100 3000)(1300 3000);
WIRE 16 -1 (1100 3050)(1100 3100);
WIRE 16 -1 (1100 3050)(1300 3050);
WIRE 16 -1 (1100 3100)(1100 3150);
WIRE 16 -1 (1100 3100)(1300 3100);
WIRE 16 -1 (1100 3150)(1100 3200);
WIRE 16 -1 (1100 3150)(1300 3150);
WIRE 16 -1 (1100 3200)(1100 3250);
WIRE 16 -1 (1100 3200)(1300 3200);
WIRE 16 -1 (1100 3250)(1100 3300);
WIRE 16 -1 (1100 3250)(1300 3250);
WIRE 16 -1 (1100 3300)(1100 3350);
WIRE 16 -1 (1100 3300)(1300 3300);
WIRE 16 -1 (1100 3350)(1100 3400);
WIRE 16 -1 (1100 3350)(1300 3350);
WIRE 16 -1 (1100 3400)(1100 3450);
WIRE 16 -1 (1100 3400)(1300 3400);
WIRE 16 -1 (1100 3450)(1100 3500);
WIRE 16 -1 (1100 3450)(1300 3450);
WIRE 16 -1 (1100 3500)(1100 3550);
WIRE 16 -1 (1100 3500)(1300 3500);
WIRE 16 -1 (1100 3550)(1100 3600);
WIRE 16 -1 (1100 3550)(1300 3550);
WIRE 16 -1 (1100 3600)(1100 3650);
WIRE 16 -1 (1100 3600)(1300 3600);
WIRE 16 -1 (1100 3650)(1100 3700);
WIRE 16 -1 (1100 3650)(1300 3650);
WIRE 16 -1 (1100 3700)(1300 3700);
WIRE 17 -1 (-1600 1625)(-1600 1675);
WIRE 17 -1 (-1150 4800)(-1600 4800);
FORCEPROP 2 LAST SIG_NAME M_F_DQ<63:0>
J 0
(-1560 4810);
DISPLAY 0.617021 (-1560 4810);
PAINT ORANGE (-1560 4810);
WIRE 17 -1 (-1600 4775)(-1600 4800);
WIRE 17 -1 (-1600 1675)(-1600 1725);
WIRE 17 -1 (-1600 1725)(-1600 1775);
WIRE 17 -1 (-1600 4725)(-1600 4775);
WIRE 17 -1 (-1600 4675)(-1600 4725);
WIRE 17 -1 (-1600 1775)(-1600 1825);
WIRE 17 -1 (-1600 1825)(-1600 1875);
WIRE 17 -1 (-1600 4625)(-1600 4675);
WIRE 17 -1 (-1600 4575)(-1600 4625);
WIRE 17 -1 (-1600 1875)(-1600 1925);
WIRE 17 -1 (-1600 1925)(-1600 1975);
WIRE 17 -1 (-1600 4525)(-1600 4575);
WIRE 17 -1 (-1600 4475)(-1600 4525);
WIRE 17 -1 (-1600 1975)(-1600 2025);
WIRE 17 -1 (-1600 2025)(-1600 2075);
WIRE 17 -1 (-1600 4425)(-1600 4475);
WIRE 17 -1 (-1600 4375)(-1600 4425);
WIRE 17 -1 (-1600 2075)(-1600 2125);
WIRE 17 -1 (-1600 2125)(-1600 2175);
WIRE 17 -1 (-1600 4325)(-1600 4375);
WIRE 17 -1 (-1600 4275)(-1600 4325);
WIRE 17 -1 (-1600 2175)(-1600 2225);
WIRE 17 -1 (-1600 2225)(-1600 2275);
WIRE 17 -1 (-1600 4225)(-1600 4275);
WIRE 17 -1 (-1600 4175)(-1600 4225);
WIRE 17 -1 (-1600 2275)(-1600 2325);
WIRE 17 -1 (-1600 2325)(-1600 2375);
WIRE 17 -1 (-1600 4125)(-1600 4175);
WIRE 17 -1 (-1600 4075)(-1600 4125);
WIRE 17 -1 (-1600 2375)(-1600 2425);
WIRE 17 -1 (-1600 2425)(-1600 2475);
WIRE 17 -1 (-1600 4025)(-1600 4075);
WIRE 17 -1 (-1600 3975)(-1600 4025);
WIRE 17 -1 (-1600 2475)(-1600 2525);
WIRE 17 -1 (-1600 2525)(-1600 2575);
WIRE 17 -1 (-1600 3925)(-1600 3975);
WIRE 17 -1 (-1600 3875)(-1600 3925);
WIRE 17 -1 (-1600 2575)(-1600 2625);
WIRE 17 -1 (-1600 2625)(-1600 2675);
WIRE 17 -1 (-1600 3825)(-1600 3875);
WIRE 17 -1 (-1600 3775)(-1600 3825);
WIRE 17 -1 (-1600 2675)(-1600 2725);
WIRE 17 -1 (-1600 2725)(-1600 2775);
WIRE 17 -1 (-1600 3725)(-1600 3775);
WIRE 17 -1 (-1600 3675)(-1600 3725);
WIRE 17 -1 (-1600 2775)(-1600 2825);
WIRE 17 -1 (-1600 2825)(-1600 2875);
WIRE 17 -1 (-1600 3625)(-1600 3675);
WIRE 17 -1 (-1600 3575)(-1600 3625);
WIRE 17 -1 (-1600 2875)(-1600 2925);
WIRE 17 -1 (-1600 2925)(-1600 2975);
WIRE 17 -1 (-1600 3525)(-1600 3575);
WIRE 17 -1 (-1600 3475)(-1600 3525);
WIRE 17 -1 (-1600 2975)(-1600 3025);
WIRE 17 -1 (-1600 3025)(-1600 3075);
WIRE 17 -1 (-1600 3425)(-1600 3475);
WIRE 17 -1 (-1600 3375)(-1600 3425);
WIRE 17 -1 (-1600 3075)(-1600 3125);
WIRE 17 -1 (-1600 3125)(-1600 3175);
WIRE 17 -1 (-1600 3325)(-1600 3375);
WIRE 17 -1 (-1600 3275)(-1600 3325);
WIRE 17 -1 (-1600 3175)(-1600 3225);
WIRE 17 -1 (-1600 3225)(-1600 3275);
WIRE 17 -1 (-3725 4800)(-3200 4800);
FORCEPROP 2 LAST SIG_NAME M_F_MA<17:0>
J 0
(-3675 4810);
DISPLAY 0.617021 (-3675 4810);
PAINT ORANGE (-3675 4810);
WIRE 17 -1 (-3200 4775)(-3200 4800);
WIRE 17 -1 (-3200 4725)(-3200 4775);
WIRE 17 -1 (-3200 4675)(-3200 4725);
WIRE 17 -1 (-3200 4625)(-3200 4675);
WIRE 17 -1 (-3200 4575)(-3200 4625);
WIRE 17 -1 (-3200 4525)(-3200 4575);
WIRE 17 -1 (-3200 4475)(-3200 4525);
WIRE 17 -1 (-3200 4425)(-3200 4475);
WIRE 17 -1 (-3200 4375)(-3200 4425);
WIRE 17 -1 (-3200 4325)(-3200 4375);
WIRE 17 -1 (-3200 4275)(-3200 4325);
WIRE 17 -1 (-3200 4225)(-3200 4275);
WIRE 17 -1 (-3200 4175)(-3200 4225);
WIRE 17 -1 (-3200 4125)(-3200 4175);
WIRE 17 -1 (-3200 4075)(-3200 4125);
WIRE 17 -1 (-3200 4025)(-3200 4075);
WIRE 17 -1 (-3200 3925)(-3200 3975);
WIRE 17 -1 (-3200 3975)(-3200 4025);
WIRE 17 -1 (1525 5200)(750 5200);
FORCEPROP 2 LAST SIG_NAME M_F_DQS_DP<17:0>
J 0
(1000 5210);
DISPLAY 0.617021 (1000 5210);
PAINT ORANGE (1000 5210);
WIRE 17 -1 (750 5175)(750 5200);
WIRE 17 -1 (750 5075)(750 5175);
WIRE 17 -1 (750 4975)(750 5075);
WIRE 17 -1 (750 4875)(750 4975);
WIRE 17 -1 (750 4775)(750 4875);
WIRE 17 -1 (750 3475)(750 3575);
WIRE 17 -1 (750 4675)(750 4775);
WIRE 17 -1 (750 4575)(750 4675);
WIRE 17 -1 (750 3575)(750 3675);
WIRE 17 -1 (750 3675)(750 3775);
WIRE 17 -1 (750 4475)(750 4575);
WIRE 17 -1 (750 4375)(750 4475);
WIRE 17 -1 (750 3775)(750 3875);
WIRE 17 -1 (750 3875)(750 3975);
WIRE 17 -1 (750 4275)(750 4375);
WIRE 17 -1 (750 4175)(750 4275);
WIRE 17 -1 (750 3975)(750 4075);
WIRE 17 -1 (750 4075)(750 4175);
WIRE 17 -1 (1525 5150)(950 5150);
FORCEPROP 2 LAST SIG_NAME M_F_DQS_DN<17:0>
J 0
(1000 5160);
DISPLAY 0.617021 (1000 5160);
PAINT ORANGE (1000 5160);
WIRE 17 -1 (950 5125)(950 5150);
WIRE 17 -1 (950 5025)(950 5125);
WIRE 17 -1 (950 4925)(950 5025);
WIRE 17 -1 (950 4825)(950 4925);
WIRE 17 -1 (950 4725)(950 4825);
WIRE 17 -1 (950 4625)(950 4725);
WIRE 17 -1 (950 4525)(950 4625);
WIRE 17 -1 (950 4425)(950 4525);
WIRE 17 -1 (950 4325)(950 4425);
WIRE 17 -1 (950 3425)(950 3525);
WIRE 17 -1 (950 4225)(950 4325);
WIRE 17 -1 (950 4125)(950 4225);
WIRE 17 -1 (950 3525)(950 3625);
WIRE 17 -1 (950 3625)(950 3725);
WIRE 17 -1 (950 4025)(950 4125);
WIRE 17 -1 (950 3925)(950 4025);
WIRE 17 -1 (950 3725)(950 3825);
WIRE 17 -1 (950 3825)(950 3925);
WIRE 17 -1 (-3200 3900)(-3750 3900);
FORCEPROP 2 LAST SIG_NAME M_F_BA<1:0>
J 0
(-3700 3910);
DISPLAY 0.617021 (-3700 3910);
PAINT ORANGE (-3700 3910);
WIRE 17 -1 (-3200 3900)(-3200 3825);
WIRE 17 -1 (-3200 3775)(-3200 3825);
WIRE 17 -1 (-3200 3125)(-3200 3175);
WIRE 17 -1 (-3200 3300)(-3750 3300);
FORCEPROP 2 LAST SIG_NAME M_F_CS_N<7:0>
J 0
(-3725 3310);
DISPLAY 0.617021 (-3725 3310);
PAINT ORANGE (-3725 3310);
WIRE 17 -1 (-3200 3300)(-3200 3275);
WIRE 17 -1 (-3200 3175)(-3200 3225);
WIRE 17 -1 (-3200 3225)(-3200 3275);
WIRE 17 -1 (-3200 2375)(-3200 2425);
WIRE 17 -1 (-3200 2425)(-3200 2475);
WIRE 17 -1 (-3200 2475)(-3200 2525);
WIRE 17 -1 (-3200 2525)(-3200 2575);
WIRE 17 -1 (-3200 2575)(-3200 2625);
WIRE 17 -1 (-3200 2750)(-3750 2750);
FORCEPROP 2 LAST SIG_NAME M_F_ECC<7:0>
J 0
(-3725 2760);
DISPLAY 0.617021 (-3725 2760);
PAINT ORANGE (-3725 2760);
WIRE 17 -1 (-3200 2750)(-3200 2725);
WIRE 17 -1 (-3200 2625)(-3200 2675);
WIRE 17 -1 (-3200 2675)(-3200 2725);
WIRE 17 -1 (-3200 3050)(-3750 3050);
FORCEPROP 2 LAST SIG_NAME M_F_CKE<3:0>
J 0
(-3725 3060);
DISPLAY 0.617021 (-3725 3060);
PAINT ORANGE (-3725 3060);
WIRE 17 -1 (-3200 3050)(-3200 3025);
WIRE 17 -1 (-3200 2975)(-3200 3025);
WIRE 17 -1 (-3200 3750)(-3750 3750);
FORCEPROP 2 LAST SIG_NAME M_F_BG<1:0>
J 0
(-3700 3760);
DISPLAY 0.617021 (-3700 3760);
PAINT ORANGE (-3700 3760);
WIRE 17 -1 (-3200 3750)(-3200 3725);
WIRE 17 -1 (-3200 3675)(-3200 3725);
WIRE 17 -1 (-3200 2900)(-3750 2900);
FORCEPROP 2 LAST SIG_NAME M_F_ODT<3:0>
J 0
(-3725 2910);
DISPLAY 0.617021 (-3725 2910);
PAINT ORANGE (-3725 2910);
WIRE 17 -1 (-3200 2900)(-3200 2875);
WIRE 17 -1 (-3200 2825)(-3200 2875);
WIRE 17 -1 (-3200 3600)(-3800 3600);
FORCEPROP 2 LAST SIG_NAME M_F_CLK_DP<3:0>
J 0
(-3750 3610);
DISPLAY 0.617021 (-3750 3610);
PAINT ORANGE (-3750 3610);
WIRE 17 -1 (-3200 3600)(-3200 3575);
WIRE 17 -1 (-3200 3475)(-3200 3575);
WIRE 17 -1 (-3400 3525)(-3400 3425);
WIRE 17 -1 (-3400 3550)(-3800 3550);
FORCEPROP 2 LAST SIG_NAME M_F_CLK_DN<3:0>
J 0
(-3750 3560);
DISPLAY 0.617021 (-3750 3560);
PAINT ORANGE (-3750 3560);
WIRE 17 -1 (-3400 3550)(-3400 3525);
WIRE 16 -1 (650 5150)(450 5150);
WIRE 16 -1 (650 4350)(450 4350);
WIRE 16 -1 (850 4300)(450 4300);
WIRE 16 -1 (650 4250)(450 4250);
WIRE 16 -1 (650 4150)(450 4150);
WIRE 16 -1 (850 4100)(450 4100);
WIRE 16 -1 (650 5050)(450 5050);
WIRE 16 -1 (850 5000)(450 5000);
WIRE 16 -1 (650 4950)(450 4950);
WIRE 16 -1 (850 4900)(450 4900);
WIRE 16 -1 (650 4850)(450 4850);
WIRE 16 -1 (850 4800)(450 4800);
WIRE 16 -1 (650 4750)(450 4750);
WIRE 16 -1 (850 4700)(450 4700);
WIRE 16 -1 (650 4650)(450 4650);
WIRE 16 -1 (850 4600)(450 4600);
WIRE 16 -1 (650 4550)(450 4550);
WIRE 16 -1 (850 4500)(450 4500);
WIRE 16 -1 (650 4450)(450 4450);
WIRE 16 -1 (850 4400)(450 4400);
WIRE 16 -1 (850 4000)(450 4000);
WIRE 16 -1 (650 3950)(450 3950);
WIRE 16 -1 (650 3550)(450 3550);
WIRE 16 -1 (650 3450)(450 3450);
WIRE 16 -1 (850 3400)(450 3400);
WIRE 16 -1 (-1700 4650)(-1900 4650);
WIRE 16 -1 (-1700 4700)(-1900 4700);
WIRE 16 -1 (-1700 4750)(-1900 4750);
WIRE 16 -1 (-1700 4100)(-1900 4100);
WIRE 16 -1 (-1700 4200)(-1900 4200);
WIRE 16 -1 (-1700 4250)(-1900 4250);
WIRE 16 -1 (-1700 4300)(-1900 4300);
WIRE 16 -1 (-1700 4500)(-1900 4500);
WIRE 16 -1 (-1700 4450)(-1900 4450);
WIRE 16 -1 (-1700 4350)(-1900 4350);
WIRE 16 -1 (-1700 4400)(-1900 4400);
WIRE 16 -1 (-1700 4550)(-1900 4550);
WIRE 16 -1 (-1700 4600)(-1900 4600);
WIRE 16 -1 (-2900 4600)(-3100 4600);
WIRE 16 -1 (-2900 4450)(-3100 4450);
WIRE 16 -1 (-2900 4400)(-3100 4400);
WIRE 16 -1 (-2900 4350)(-3100 4350);
WIRE 16 -1 (-2900 4300)(-3100 4300);
WIRE 16 -1 (-2900 4250)(-3100 4250);
WIRE 16 -1 (-2900 4200)(-3100 4200);
WIRE 16 -1 (-2900 4150)(-3100 4150);
WIRE 16 -1 (-2900 4100)(-3100 4100);
WIRE 16 -1 (-2900 4750)(-3100 4750);
WIRE 16 -1 (-2900 4500)(-3100 4500);
WIRE 16 -1 (-1700 3850)(-1900 3850);
WIRE 16 -1 (-1700 3400)(-1900 3400);
WIRE 16 -1 (-1700 3350)(-1900 3350);
WIRE 16 -1 (-1700 3100)(-1900 3100);
WIRE 16 -1 (-1700 3150)(-1900 3150);
WIRE 16 -1 (-1700 3250)(-1900 3250);
WIRE 16 -1 (-1700 3300)(-1900 3300);
WIRE 16 -1 (-1700 3450)(-1900 3450);
WIRE 16 -1 (-1700 2950)(-1900 2950);
WIRE 16 -1 (-1700 2600)(-1900 2600);
WIRE 16 -1 (-1700 2650)(-1900 2650);
WIRE 16 -1 (-1700 2700)(-1900 2700);
WIRE 16 -1 (-1700 2800)(-1900 2800);
WIRE 16 -1 (-1700 2100)(-1900 2100);
WIRE 16 -1 (-1700 2450)(-1900 2450);
WIRE 16 -1 (-1700 2350)(-1900 2350);
WIRE 16 -1 (-1700 2050)(-1900 2050);
WIRE 16 -1 (-1700 2150)(-1900 2150);
WIRE 16 -1 (-1700 2200)(-1900 2200);
WIRE 16 -1 (-1700 2250)(-1900 2250);
WIRE 16 -1 (-1700 2300)(-1900 2300);
WIRE 16 -1 (-1700 2400)(-1900 2400);
WIRE 16 -1 (-1700 2500)(-1900 2500);
WIRE 16 -1 (-1700 2550)(-1900 2550);
WIRE 16 -1 (-1700 1850)(-1900 1850);
WIRE 16 -1 (-1700 1800)(-1900 1800);
WIRE 16 -1 (-1700 1750)(-1900 1750);
WIRE 16 -1 (-1700 1700)(-1900 1700);
WIRE 16 -1 (-1700 1900)(-1900 1900);
WIRE 16 -1 (-1700 1950)(-1900 1950);
WIRE 16 -1 (-1700 2000)(-1900 2000);
WIRE 16 -1 (-3050 3300)(-2900 3300);
WIRE 16 -1 (-3050 3350)(-3750 3350);
FORCEPROP 2 LAST SIG_NAME M_F_C<2>
J 0
(-3725 3360);
DISPLAY 0.617021 (-3725 3360);
PAINT ORANGE (-3725 3360);
WIRE 16 -1 (-3050 3350)(-3050 3300);
WIRE 16 -1 (-2900 2100)(-3925 2100);
FORCEPROP 2 LAST SIG_NAME M_F_ALERT_N
J 0
(-3875 2110);
DISPLAY 0.617021 (-3875 2110);
PAINT ORANGE (-3875 2110);
WIRE 16 -1 (-2900 2050)(-3900 2050);
FORCEPROP 2 LAST SIG_NAME M_F_ACT_N
J 0
(-3875 2060);
DISPLAY 0.617021 (-3875 2060);
PAINT ORANGE (-3875 2060);
WIRE 16 -1 (-2900 3400)(-3300 3400);
WIRE 16 -1 (-2900 3500)(-3300 3500);
WIRE 16 -1 (-2900 3550)(-3100 3550);
WIRE 16 -1 (-2900 3450)(-3100 3450);
WIRE 16 -1 (-2900 2950)(-3100 2950);
WIRE 16 -1 (-2900 3100)(-3100 3100);
WIRE 16 -1 (-2900 2850)(-3100 2850);
WIRE 16 -1 (-2900 2800)(-3100 2800);
WIRE 16 -1 (-2900 2700)(-3100 2700);
WIRE 16 -1 (-2900 4000)(-3100 4000);
WIRE 16 -1 (-2900 3750)(-3100 3750);
WIRE 16 -1 (-2900 3700)(-3100 3700);
WIRE 16 -1 (-2900 3650)(-3100 3650);
WIRE 16 -1 (-2900 3000)(-3100 3000);
WIRE 16 -1 (-2900 2350)(-3100 2350);
WIRE 16 -1 (-2900 2400)(-3100 2400);
WIRE 16 -1 (-2900 2450)(-3100 2450);
WIRE 16 -1 (-2900 2500)(-3100 2500);
WIRE 16 -1 (-2900 2550)(-3100 2550);
WIRE 16 -1 (-2900 2600)(-3100 2600);
WIRE 16 -1 (-2900 2650)(-3100 2650);
WIRE 16 -1 (-2900 4050)(-3100 4050);
WIRE 16 -1 (-2900 3900)(-3100 3900);
WIRE 16 -1 (-2900 3150)(-3100 3150);
WIRE 16 -1 (-2900 3200)(-3100 3200);
WIRE 16 -1 (-2900 3250)(-3100 3250);
WIRE 16 -1 (-2900 3800)(-3100 3800);
WIRE 16 -1 (-3300 2650)(-3750 2650);
FORCEPROP 2 LAST SIG_NAME M_DEF_RST_N
J 0
(-3725 2660);
DISPLAY 0.617021 (-3725 2660);
PAINT ORANGE (-3725 2660);
WIRE 16 -1 (-3300 2200)(-3300 2650);
WIRE 16 -1 (-2900 2200)(-3300 2200);
WIRE 16 -1 (-3250 2700)(-3750 2700);
FORCEPROP 2 LAST SIG_NAME M_F_PAR
J 0
(-3725 2710);
DISPLAY 0.617021 (-3725 2710);
PAINT ORANGE (-3725 2710);
WIRE 16 -1 (-3250 2250)(-3250 2700);
WIRE 16 -1 (-2900 2250)(-3250 2250);
WIRE 16 -1 (-3350 2150)(-2900 2150);
WIRE 16 -1 (-3350 2400)(-4075 2400);
FORCEPROP 2 LAST SIG_NAME FM_DIMM_EVENT_COD_N
J 0
(-4007 2400);
DISPLAY 0.617021 (-4007 2400);
PAINT ORANGE (-4007 2400);
WIRE 16 -1 (-3350 2400)(-3350 2150);
WIRE 16 -1 (-3750 1300)(-2900 1300);
FORCEPROP 2 LAST SIG_NAME FM_ADR_COMPLETE_DEF_N
J 0
(-3700 1310);
DISPLAY 0.617021 (-3700 1310);
PAINT ORANGE (-3700 1310);
WIRE 16 -1 (-3750 1750)(-2900 1750);
FORCEPROP 2 LAST SIG_NAME SMB_DDR_DEF_VPP_SDA
J 0
(-3710 1760);
DISPLAY 0.617021 (-3710 1760);
PAINT ORANGE (-3710 1760);
WIRE 16 -1 (-3750 1700)(-2900 1700);
FORCEPROP 2 LAST SIG_NAME SMB_DDR_DEF_VPP_SCL
J 0
(-3710 1710);
DISPLAY 0.617021 (-3710 1710);
PAINT ORANGE (-3710 1710);
WIRE 16 -1 (-3750 1450)(-2900 1450);
FORCEPROP 2 LAST SIG_NAME TP_CH_F_DIMM_F1_RFU_1
J 0
(-3700 1460);
DISPLAY 0.617021 (-3700 1460);
PAINT ORANGE (-3700 1460);
FORCEPROP 2 LASTPROP $XRERR UNIQUE?
J 0
(-3990 1450);
DISPLAY 0.638298 (-3990 1450);
PAINT MONO (-3990 1450);
DISPLAY INVISIBLE (-3990 1450);
WIRE 16 -1 (-3750 1400)(-2900 1400);
FORCEPROP 2 LAST SIG_NAME TP_CH_F_DIMM_F1_RFU_0
J 0
(-3700 1410);
DISPLAY 0.617021 (-3700 1410);
PAINT ORANGE (-3700 1410);
FORCEPROP 2 LASTPROP $XRERR UNIQUE?
J 0
(-3990 1400);
DISPLAY 0.638298 (-3990 1400);
PAINT MONO (-3990 1400);
DISPLAY INVISIBLE (-3990 1400);
WIRE 16 -1 (-3750 1500)(-2900 1500);
FORCEPROP 2 LAST SIG_NAME TP_CH_F_DIMM_F1_RFU_2
J 0
(-3700 1510);
DISPLAY 0.617021 (-3700 1510);
PAINT ORANGE (-3700 1510);
FORCEPROP 2 LASTPROP $XRERR UNIQUE?
J 0
(-3990 1500);
DISPLAY 0.638298 (-3990 1500);
PAINT MONO (-3990 1500);
DISPLAY INVISIBLE (-3990 1500);
WIRE 16 -1 (-4600 1600)(-4600 1500);
WIRE 16 -1 (-2900 1600)(-4600 1600);
FORCEPROP 2 LAST SIG_NAME M_F_VREF
J 0
(-3700 1610);
DISPLAY 0.617021 (-3700 1610);
PAINT ORANGE (-3700 1610);
WIRE 16 -1 (-4700 1600)(-4600 1600);
WIRE 16 -1 (-1700 1600)(-1900 1600);
WIRE 16 -1 (-1700 1650)(-1900 1650);
WIRE 16 -1 (850 5100)(450 5100);
WIRE 16 -1 (850 4200)(450 4200);
WIRE 16 -1 (-1700 4150)(-1900 4150);
WIRE 16 -1 (-1700 4050)(-1900 4050);
WIRE 16 -1 (-1700 4000)(-1900 4000);
WIRE 16 -1 (-1700 3950)(-1900 3950);
WIRE 16 -1 (-1700 3800)(-1900 3800);
WIRE 16 -1 (-1700 3750)(-1900 3750);
WIRE 16 -1 (-1700 3700)(-1900 3700);
WIRE 16 -1 (-1700 3650)(-1900 3650);
WIRE 16 -1 (-1700 3600)(-1900 3600);
WIRE 16 -1 (-1700 3550)(-1900 3550);
WIRE 16 -1 (-1700 3500)(-1900 3500);
WIRE 16 -1 (-2900 4550)(-3100 4550);
WIRE 16 -1 (-2900 4650)(-3100 4650);
WIRE 16 -1 (-2900 4700)(-3100 4700);
WIRE 16 -1 (850 3500)(450 3500);
WIRE 16 -1 (850 3600)(450 3600);
WIRE 16 -1 (650 3650)(450 3650);
WIRE 16 -1 (650 3850)(450 3850);
WIRE 16 -1 (850 3900)(450 3900);
WIRE 16 -1 (850 3700)(450 3700);
WIRE 16 -1 (650 3750)(450 3750);
WIRE 16 -1 (850 3800)(450 3800);
WIRE 16 -1 (650 4050)(450 4050);
WIRE 16 -1 (-1700 3900)(-1900 3900);
WIRE 16 -1 (-2900 3950)(-3100 3950);
WIRE 16 -1 (-1700 2750)(-1900 2750);
WIRE 16 -1 (-1700 2850)(-1900 2850);
WIRE 16 -1 (-1700 2900)(-1900 2900);
WIRE 16 -1 (-1700 3000)(-1900 3000);
WIRE 16 -1 (-1700 3050)(-1900 3050);
WIRE 16 -1 (-1700 3200)(-1900 3200);
DOT 1 (1100 3100);
DOT 1 (2500 3250);
DOT 1 (1100 3350);
DOT 1 (1100 2900);
DOT 1 (1100 2850);
DOT 1 (1100 2800);
DOT 1 (1100 1650);
DOT 1 (-750 1250);
DOT 1 (-750 2600);
DOT 1 (-750 2750);
DOT 1 (1100 3000);
DOT 1 (650 2750);
DOT 1 (-750 2300);
DOT 1 (-750 2150);
DOT 1 (-750 2450);
DOT 1 (-750 1150);
DOT 1 (-750 1100);
DOT 1 (-750 1200);
DOT 1 (-750 1400);
DOT 1 (-750 1350);
DOT 1 (-750 1500);
DOT 1 (-750 1550);
DOT 1 (-750 1650);
DOT 1 (-750 1600);
DOT 1 (-750 1700);
DOT 1 (-750 1800);
DOT 1 (-750 1750);
DOT 1 (-750 1900);
DOT 1 (-750 1850);
DOT 1 (-750 1950);
DOT 1 (-750 2050);
DOT 1 (-750 2000);
DOT 1 (-750 2200);
DOT 1 (-750 2100);
DOT 1 (-750 2250);
DOT 1 (-750 2700);
DOT 1 (-750 2650);
DOT 1 (2500 3650);
DOT 1 (2500 3600);
DOT 1 (2500 3550);
DOT 1 (2500 3500);
DOT 1 (2500 3450);
DOT 1 (2500 3400);
DOT 1 (2500 3350);
DOT 1 (2500 3300);
DOT 1 (2500 3200);
DOT 1 (2500 3150);
DOT 1 (2500 3100);
DOT 1 (2500 3050);
DOT 1 (2500 3000);
DOT 1 (2500 2900);
DOT 1 (2500 2850);
DOT 1 (2500 2800);
DOT 1 (2500 2750);
DOT 1 (2500 2700);
DOT 1 (2500 2650);
DOT 1 (2500 2600);
DOT 1 (2500 2550);
DOT 1 (2500 2500);
DOT 1 (2500 2450);
DOT 1 (2500 2400);
DOT 1 (2500 2350);
DOT 1 (2500 2300);
DOT 1 (2500 2250);
DOT 1 (2500 2200);
DOT 1 (2500 2100);
DOT 1 (2500 2150);
DOT 1 (2500 2050);
DOT 1 (2500 2000);
DOT 1 (2500 1950);
DOT 1 (2500 1900);
DOT 1 (2500 1850);
DOT 1 (2500 1800);
DOT 1 (2500 1750);
DOT 1 (2500 1700);
DOT 1 (2500 1650);
DOT 1 (2500 1600);
DOT 1 (2500 1550);
DOT 1 (2500 1500);
DOT 1 (2500 1450);
DOT 1 (2500 1400);
DOT 1 (1100 3650);
DOT 1 (1100 3600);
DOT 1 (1100 3550);
DOT 1 (1100 3500);
DOT 1 (1100 3400);
DOT 1 (1100 3450);
DOT 1 (1100 3250);
DOT 1 (1100 3300);
DOT 1 (1100 3200);
DOT 1 (1100 3150);
DOT 1 (1100 3050);
DOT 1 (1100 2950);
DOT 1 (1100 2750);
DOT 1 (1100 2700);
DOT 1 (1100 2650);
DOT 1 (1100 2600);
DOT 1 (1100 2500);
DOT 1 (1100 2550);
DOT 1 (1100 2450);
DOT 1 (1100 2400);
DOT 1 (1100 2350);
DOT 1 (1100 2300);
DOT 1 (1100 2250);
DOT 1 (1100 2200);
DOT 1 (1100 2100);
DOT 1 (1100 2150);
DOT 1 (1100 2050);
DOT 1 (1100 2000);
DOT 1 (1100 1950);
DOT 1 (1100 1850);
DOT 1 (1100 1800);
DOT 1 (1100 1700);
DOT 1 (1100 1750);
DOT 1 (1100 1600);
DOT 1 (1100 1500);
DOT 1 (1100 1450);
DOT 1 (1100 1400);
DOT 1 (-750 1450);
DOT 1 (-750 1300);
DOT 1 (1100 1550);
DOT 1 (1100 1900);
DOT 1 (-3100 1900);
DOT 1 (-3100 1950);
DOT 1 (-4600 1600);
DOT 1 (2500 2950);
FORCENOTE
PVDDQ (SINGLE SIDE) CAP: 10UF X1, 22UF X50
(-2925 5225) 0;
DISPLAY LEFT (-2925 5225);
DISPLAY 1.021277 (-2925 5225);
PAINT PURPLE (-2925 5225);
FORCENOTE
PVTT CAP: 100UF X2, 47UF X1
(-2925 5275) 0;
DISPLAY LEFT (-2925 5275);
DISPLAY 1.021277 (-2925 5275);
PAINT PURPLE (-2925 5275);
FORCENOTE
PVDDQ (DOUBLE SIDE) CAP: 100UF X8, 47UF X41
(-2925 5175) 0;
DISPLAY LEFT (-2925 5175);
DISPLAY 1.021277 (-2925 5175);
PAINT PURPLE (-2925 5175);
FORCENOTE
PVPP CAP: 10UF X12
(-2925 5325) 0;
DISPLAY LEFT (-2925 5325);
DISPLAY 1.021277 (-2925 5325);
PAINT PURPLE (-2925 5325);
FORCENOTE
CAP BETWEEN DIMM
(-2925 5400) 0;
DISPLAY LEFT (-2925 5400);
DISPLAY 1.276596 (-2925 5400);
PAINT PURPLE (-2925 5400);
FORCENOTE
SMBUS ADDR: 0XAA
(-5275 759) 0;
DISPLAY LEFT (-5275 759);
DISPLAY 1.957447 (-5275 759);
PAINT PURPLE (-5275 759);
FORCENOTE
PLACE CAP NEAR DIMM CONNECTOR
(-5288 1052) 0;
DISPLAY LEFT (-5288 1052);
DISPLAY 1.595745 (-5288 1052);
PAINT PURPLE (-5288 1052);
QUIT
